FILE_TYPE = MACRO_DRAWING;
SET COLOR_WIRE YELLOW;
SET COLOR_PROP ORANGE;
SET COLOR_DOT WHITE;
SET COLOR_ARC YELLOW;
SET COLOR_BODY GREEN;
SET COLOR_NOTE PURPLE;
SET PROP_DISPLAY VALUE;
SET PAGE_NUMBER P408;
FORCEADD OFFPAGE..1
(-8050 1200);
FORCEPROP 2 LAST $XR0 182 
J 0
(-8332 1200);
DISPLAY 0.638298 (-8332 1200);
PAINT MONO (-8332 1200);
FORCEPROP 2 LAST CDS_LIB standard
J 0
(-8050 1200);
DISPLAY INVISIBLE (-8050 1200);
FORCEPROP 1 LAST OFFPAGE TRUE
J 0
(-7725 1075);
DISPLAY 0.872340 (-7725 1075);
DISPLAY INVISIBLE (-7725 1075);
FORCEPROP 1 LAST COMMENT_BODY TRUE
J 0
(-7925 1100);
DISPLAY 0.872340 (-7925 1100);
PAINT GREEN (-7925 1100);
DISPLAY INVISIBLE (-7925 1100);
FORCEPROP 2 LAST PATH I1
J 0
(-8325 1250);
DISPLAY 0.680851 (-8325 1250);
DISPLAY INVISIBLE (-8325 1250);
FORCEADD Q_RES..2
(-8950 6000);
FORCEPROP 1 LAST LOCATION R1027
J 0
(-8905 6125);
DISPLAY 0.787234 (-8905 6125);
FORCEPROP 0 LAST $SEC 1
J 0
(-8900 6175);
DISPLAY 0.680851 (-8900 6175);
PAINT MONO (-8900 6175);
DISPLAY INVISIBLE (-8900 6175);
FORCEPROP 0 LAST CDS_SEC 1
J 0
(-8900 6175);
DISPLAY 0.680851 (-8900 6175);
DISPLAY INVISIBLE (-8900 6175);
FORCEPROP 1 LASTPIN (-8950 6100) $PN 1
J 0
(-8945 6062);
DISPLAY 0.787234 (-8945 6062);
PAINT MONO (-8945 6062);
FORCEPROP 1 LASTPIN (-8950 5900) $PN 2
J 0
(-8945 5910);
DISPLAY 0.787234 (-8945 5910);
PAINT MONO (-8945 5910);
FORCEPROP 1 LAST TOLERANCE 5%
J 0
(-8905 6025);
DISPLAY 0.787234 (-8905 6025);
FORCEPROP 1 LAST PACK_TYPE 0201LF
J 0
(-8900 5850);
DISPLAY 0.787234 (-8900 5850);
FORCEPROP 1 LAST MATERIAL EMPTY
J 0
(-8910 5925);
DISPLAY 0.787234 (-8910 5925);
FORCEPROP 1 LAST WATTAGE 1/20W
J 0
(-8910 5975);
DISPLAY 0.787234 (-8910 5975);
FORCEPROP 1 LAST VALUE 4.7K
J 0
(-8905 6075);
DISPLAY 0.787234 (-8905 6075);
FORCEPROP 2 LAST CDS_LIB pure_quanta
J 0
(-8950 6000);
DISPLAY INVISIBLE (-8950 6000);
FORCEPROP 1 LAST PATH I10
J 0
(-8900 6175);
DISPLAY 0.978723 (-8900 6175);
PAINT WHITE (-8900 6175);
DISPLAY INVISIBLE (-8900 6175);
FORCEPROP 1 LAST PART_NUMBER CS24701JE04
J 0
(-8910 5875);
DISPLAY 0.978723 (-8910 5875);
DISPLAY INVISIBLE (-8910 5875);
FORCEADD P1V0..1
(-1275 4100);
FORCEPROP 3 LASTPIN (-1275 4050) SIG_NAME P1V8_CPU0_RT_1D\g
J 0
(-1265 4060);
DISPLAY 0.659574 (-1265 4060);
PAINT MONO (-1265 4060);
DISPLAY INVISIBLE (-1265 4060);
FORCEPROP 1 LAST HDL_POWER P1V8_CPU0_RT_1D
J 1
(-1275 4150);
DISPLAY 0.489362 (-1275 4150);
PAINT SKYBLUE (-1275 4150);
FORCEPROP 2 LAST CDS_LIB pure_quanta_power
J 0
(-1275 4100);
DISPLAY INVISIBLE (-1275 4100);
FORCEPROP 1 LAST PATH I100
J 0
(-1225 4125);
DISPLAY 0.872340 (-1225 4125);
PAINT AQUA (-1225 4125);
DISPLAY INVISIBLE (-1225 4125);
FORCEADD OFFPAGE..1
R 2
(-425 3425);
FORCEPROP 2 LAST $XR0 288 
J 0
(-239 3425);
DISPLAY 0.638298 (-239 3425);
PAINT MONO (-239 3425);
FORCEPROP 2 LAST CDS_LIB standard
J 0
(-425 3425);
DISPLAY INVISIBLE (-425 3425);
FORCEPROP 1 LAST OFFPAGE TRUE
J 2
(-750 3300);
DISPLAY 0.872340 (-750 3300);
DISPLAY INVISIBLE (-750 3300);
FORCEPROP 1 LAST COMMENT_BODY TRUE
J 2
(-550 3325);
DISPLAY 0.872340 (-550 3325);
PAINT GREEN (-550 3325);
DISPLAY INVISIBLE (-550 3325);
FORCEPROP 2 LAST PATH I101
J 0
(-250 3500);
DISPLAY 0.680851 (-250 3500);
DISPLAY INVISIBLE (-250 3500);
FORCEADD Q_RES..2
(-8975 3450);
FORCEPROP 1 LAST LOCATION R1022
J 0
(-8930 3575);
DISPLAY 0.978723 (-8930 3575);
PAINT WHITE (-8930 3575);
FORCEPROP 0 LAST $SEC 1
J 0
(-8925 3625);
DISPLAY 0.680851 (-8925 3625);
PAINT MONO (-8925 3625);
DISPLAY INVISIBLE (-8925 3625);
FORCEPROP 0 LAST CDS_SEC 1
J 0
(-8925 3625);
DISPLAY 0.680851 (-8925 3625);
DISPLAY INVISIBLE (-8925 3625);
FORCEPROP 1 LASTPIN (-8975 3550) $PN 1
J 0
(-8970 3512);
DISPLAY 0.787234 (-8970 3512);
PAINT MONO (-8970 3512);
FORCEPROP 1 LASTPIN (-8975 3350) $PN 2
J 0
(-8970 3360);
DISPLAY 0.787234 (-8970 3360);
PAINT MONO (-8970 3360);
FORCEPROP 1 LAST PACK_TYPE 0201LF
J 0
(-8935 3275);
DISPLAY 0.978723 (-8935 3275);
FORCEPROP 1 LAST MATERIAL CHIP
J 0
(-8935 3375);
DISPLAY 0.978723 (-8935 3375);
FORCEPROP 1 LAST TOLERANCE 1%
J 0
(-8930 3475);
DISPLAY 0.978723 (-8930 3475);
FORCEPROP 1 LAST VALUE 200
J 0
(-8930 3525);
DISPLAY 0.978723 (-8930 3525);
FORCEPROP 1 LAST WATTAGE 1/20W
J 0
(-8935 3425);
DISPLAY 0.978723 (-8935 3425);
FORCEPROP 2 LAST CDS_LIB pure_quanta
J 0
(-8975 3450);
DISPLAY INVISIBLE (-8975 3450);
FORCEPROP 1 LAST PATH I102
J 0
(-8925 3625);
DISPLAY 0.978723 (-8925 3625);
PAINT WHITE (-8925 3625);
DISPLAY INVISIBLE (-8925 3625);
FORCEPROP 1 LAST PART_NUMBER CS12001FE12
J 0
(-8935 3325);
DISPLAY 0.978723 (-8935 3325);
DISPLAY INVISIBLE (-8935 3325);
FORCEADD OFFPAGE..5
(-2800 950);
FORCEPROP 2 LAST $XR0 288 
J 0
(-3085 950);
DISPLAY 0.638298 (-3085 950);
PAINT MONO (-3085 950);
FORCEPROP 2 LAST CDS_LIB standard
J 0
(-2800 950);
DISPLAY INVISIBLE (-2800 950);
FORCEPROP 1 LAST OFFPAGE TRUE
J 0
(-2475 825);
DISPLAY 0.872340 (-2475 825);
PAINT GREEN (-2475 825);
DISPLAY INVISIBLE (-2475 825);
FORCEPROP 1 LAST COMMENT_BODY TRUE
J 0
(-2700 875);
DISPLAY 0.872340 (-2700 875);
PAINT GREEN (-2700 875);
DISPLAY INVISIBLE (-2700 875);
FORCEPROP 2 LAST PATH I103
J 0
(-2750 1025);
DISPLAY 0.680851 (-2750 1025);
DISPLAY INVISIBLE (-2750 1025);
FORCEADD OFFPAGE..5
(-2800 1000);
FORCEPROP 2 LAST $XR0 288 
J 0
(-3085 1000);
DISPLAY 0.638298 (-3085 1000);
PAINT MONO (-3085 1000);
FORCEPROP 2 LAST CDS_LIB standard
J 0
(-2800 1000);
DISPLAY INVISIBLE (-2800 1000);
FORCEPROP 1 LAST OFFPAGE TRUE
J 0
(-2475 875);
DISPLAY 0.872340 (-2475 875);
PAINT GREEN (-2475 875);
DISPLAY INVISIBLE (-2475 875);
FORCEPROP 1 LAST COMMENT_BODY TRUE
J 0
(-2700 925);
DISPLAY 0.872340 (-2700 925);
PAINT GREEN (-2700 925);
DISPLAY INVISIBLE (-2700 925);
FORCEPROP 2 LAST PATH I105
J 0
(-2750 1075);
DISPLAY 0.680851 (-2750 1075);
DISPLAY INVISIBLE (-2750 1075);
FORCEADD OFFPAGE..5
(-2800 1050);
FORCEPROP 2 LAST $XR0 288 
J 0
(-3085 1050);
DISPLAY 0.638298 (-3085 1050);
PAINT MONO (-3085 1050);
FORCEPROP 2 LAST CDS_LIB standard
J 0
(-2800 1050);
DISPLAY INVISIBLE (-2800 1050);
FORCEPROP 1 LAST OFFPAGE TRUE
J 0
(-2475 925);
DISPLAY 0.872340 (-2475 925);
PAINT GREEN (-2475 925);
DISPLAY INVISIBLE (-2475 925);
FORCEPROP 1 LAST COMMENT_BODY TRUE
J 0
(-2700 975);
DISPLAY 0.872340 (-2700 975);
PAINT GREEN (-2700 975);
DISPLAY INVISIBLE (-2700 975);
FORCEPROP 2 LAST PATH I106
J 0
(-2750 1125);
DISPLAY 0.680851 (-2750 1125);
DISPLAY INVISIBLE (-2750 1125);
FORCEADD OFFPAGE..5
(-2800 1100);
FORCEPROP 2 LAST $XR0 288 
J 0
(-3085 1100);
DISPLAY 0.638298 (-3085 1100);
PAINT MONO (-3085 1100);
FORCEPROP 2 LAST CDS_LIB standard
J 2
(-2800 1100);
DISPLAY INVISIBLE (-2800 1100);
FORCEPROP 1 LAST OFFPAGE TRUE
J 0
(-2475 975);
DISPLAY 0.872340 (-2475 975);
PAINT GREEN (-2475 975);
DISPLAY INVISIBLE (-2475 975);
FORCEPROP 1 LAST COMMENT_BODY TRUE
J 0
(-2700 1025);
DISPLAY 0.872340 (-2700 1025);
PAINT GREEN (-2700 1025);
DISPLAY INVISIBLE (-2700 1025);
FORCEPROP 2 LAST PATH I107
J 0
(-2750 1175);
DISPLAY 0.680851 (-2750 1175);
DISPLAY INVISIBLE (-2750 1175);
FORCEADD Q_RES..2
(-8325 6000);
FORCEPROP 1 LAST LOCATION R1030
J 0
(-8280 6125);
DISPLAY 0.787234 (-8280 6125);
FORCEPROP 0 LAST $SEC 1
J 0
(-8275 6175);
DISPLAY 0.680851 (-8275 6175);
PAINT MONO (-8275 6175);
DISPLAY INVISIBLE (-8275 6175);
FORCEPROP 0 LAST CDS_SEC 1
J 0
(-8275 6175);
DISPLAY 0.680851 (-8275 6175);
DISPLAY INVISIBLE (-8275 6175);
FORCEPROP 1 LASTPIN (-8325 6100) $PN 1
J 0
(-8320 6062);
DISPLAY 0.787234 (-8320 6062);
PAINT MONO (-8320 6062);
FORCEPROP 1 LASTPIN (-8325 5900) $PN 2
J 0
(-8320 5910);
DISPLAY 0.787234 (-8320 5910);
PAINT MONO (-8320 5910);
FORCEPROP 1 LAST VALUE 4.7K
J 0
(-8280 6075);
DISPLAY 0.787234 (-8280 6075);
FORCEPROP 1 LAST MATERIAL EMPTY
J 0
(-8285 5925);
DISPLAY 0.787234 (-8285 5925);
FORCEPROP 1 LAST PACK_TYPE 0201LF
J 0
(-8275 5850);
DISPLAY 0.787234 (-8275 5850);
FORCEPROP 1 LAST WATTAGE 1/20W
J 0
(-8285 5975);
DISPLAY 0.787234 (-8285 5975);
FORCEPROP 1 LAST TOLERANCE 5%
J 0
(-8280 6025);
DISPLAY 0.787234 (-8280 6025);
FORCEPROP 2 LAST CDS_LIB pure_quanta
J 0
(-8325 6000);
DISPLAY INVISIBLE (-8325 6000);
FORCEPROP 1 LAST PATH I11
J 0
(-8275 6175);
DISPLAY 0.978723 (-8275 6175);
PAINT WHITE (-8275 6175);
DISPLAY INVISIBLE (-8275 6175);
FORCEPROP 1 LAST PART_NUMBER CS24701JE04
J 0
(-8285 5875);
DISPLAY 0.978723 (-8285 5875);
DISPLAY INVISIBLE (-8285 5875);
FORCEADD Q_RES..2
(-1650 1350);
FORCEPROP 1 LAST LOCATION R1470
J 0
(-1605 1475);
DISPLAY 0.978723 (-1605 1475);
FORCEPROP 0 LAST $SEC 1
J 0
(-1600 1525);
DISPLAY 0.680851 (-1600 1525);
PAINT MONO (-1600 1525);
DISPLAY INVISIBLE (-1600 1525);
FORCEPROP 0 LAST CDS_SEC 1
J 0
(-1600 1525);
DISPLAY 0.680851 (-1600 1525);
DISPLAY INVISIBLE (-1600 1525);
FORCEPROP 1 LASTPIN (-1650 1450) $PN 1
J 0
(-1645 1412);
DISPLAY 0.787234 (-1645 1412);
PAINT MONO (-1645 1412);
FORCEPROP 1 LASTPIN (-1650 1250) $PN 2
J 0
(-1645 1260);
DISPLAY 0.787234 (-1645 1260);
PAINT MONO (-1645 1260);
FORCEPROP 1 LAST PACK_TYPE 0201LF
J 0
(-1600 1200);
DISPLAY 0.787234 (-1600 1200);
FORCEPROP 1 LAST VALUE 4.7K
J 0
(-1605 1425);
DISPLAY 0.787234 (-1605 1425);
FORCEPROP 1 LAST TOLERANCE 5%
J 0
(-1605 1375);
DISPLAY 0.787234 (-1605 1375);
FORCEPROP 1 LAST WATTAGE 1/20W
J 0
(-1610 1325);
DISPLAY 0.787234 (-1610 1325);
FORCEPROP 1 LAST MATERIAL EMPTY
J 0
(-1610 1275);
DISPLAY 0.787234 (-1610 1275);
PAINT RED (-1610 1275);
FORCEPROP 2 LAST CDS_LIB pure_quanta
J 0
(-1650 1350);
DISPLAY INVISIBLE (-1650 1350);
FORCEPROP 1 LAST PATH I115
J 0
(-1600 1525);
DISPLAY 0.978723 (-1600 1525);
PAINT WHITE (-1600 1525);
DISPLAY INVISIBLE (-1600 1525);
FORCEPROP 1 LAST PART_NUMBER CS24701JE04
J 0
(-1610 1225);
DISPLAY 0.978723 (-1610 1225);
DISPLAY INVISIBLE (-1610 1225);
FORCEADD Q_RES..2
(-1375 1350);
FORCEPROP 1 LAST LOCATION R1471
J 0
(-1330 1475);
DISPLAY 0.978723 (-1330 1475);
FORCEPROP 0 LAST $SEC 1
J 0
(-1325 1525);
DISPLAY 0.680851 (-1325 1525);
PAINT MONO (-1325 1525);
DISPLAY INVISIBLE (-1325 1525);
FORCEPROP 0 LAST CDS_SEC 1
J 0
(-1325 1525);
DISPLAY 0.680851 (-1325 1525);
DISPLAY INVISIBLE (-1325 1525);
FORCEPROP 1 LASTPIN (-1375 1450) $PN 1
J 0
(-1370 1412);
DISPLAY 0.787234 (-1370 1412);
PAINT MONO (-1370 1412);
FORCEPROP 1 LASTPIN (-1375 1250) $PN 2
J 0
(-1370 1260);
DISPLAY 0.787234 (-1370 1260);
PAINT MONO (-1370 1260);
FORCEPROP 1 LAST MATERIAL EMPTY
J 0
(-1335 1275);
DISPLAY 0.787234 (-1335 1275);
PAINT RED (-1335 1275);
FORCEPROP 1 LAST WATTAGE 1/20W
J 0
(-1335 1325);
DISPLAY 0.787234 (-1335 1325);
FORCEPROP 1 LAST TOLERANCE 5%
J 0
(-1330 1375);
DISPLAY 0.787234 (-1330 1375);
FORCEPROP 1 LAST VALUE 4.7K
J 0
(-1330 1425);
DISPLAY 0.787234 (-1330 1425);
FORCEPROP 1 LAST PACK_TYPE 0201LF
J 0
(-1325 1200);
DISPLAY 0.787234 (-1325 1200);
FORCEPROP 2 LAST CDS_LIB pure_quanta
J 0
(-1375 1350);
DISPLAY INVISIBLE (-1375 1350);
FORCEPROP 1 LAST PATH I116
J 0
(-1325 1525);
DISPLAY 0.978723 (-1325 1525);
PAINT WHITE (-1325 1525);
DISPLAY INVISIBLE (-1325 1525);
FORCEPROP 1 LAST PART_NUMBER CS24701JE04
J 0
(-1335 1225);
DISPLAY 0.978723 (-1335 1225);
DISPLAY INVISIBLE (-1335 1225);
FORCEADD Q_RES..2
(-825 725);
FORCEPROP 1 LAST LOCATION R1392
J 0
(-780 850);
DISPLAY 0.787234 (-780 850);
FORCEPROP 0 LAST $SEC 1
J 0
(-775 900);
DISPLAY 0.680851 (-775 900);
PAINT MONO (-775 900);
DISPLAY INVISIBLE (-775 900);
FORCEPROP 0 LAST CDS_SEC 1
J 0
(-775 900);
DISPLAY 0.680851 (-775 900);
DISPLAY INVISIBLE (-775 900);
FORCEPROP 1 LASTPIN (-825 825) $PN 1
J 0
(-820 787);
DISPLAY 0.787234 (-820 787);
PAINT MONO (-820 787);
FORCEPROP 1 LASTPIN (-825 625) $PN 2
J 0
(-820 635);
DISPLAY 0.787234 (-820 635);
PAINT MONO (-820 635);
FORCEPROP 1 LAST TOLERANCE 5%
J 0
(-780 750);
DISPLAY 0.787234 (-780 750);
FORCEPROP 1 LAST VALUE 4.7K
J 0
(-780 800);
DISPLAY 0.787234 (-780 800);
FORCEPROP 1 LAST WATTAGE 1/20W
J 0
(-785 700);
DISPLAY 0.787234 (-785 700);
FORCEPROP 1 LAST MATERIAL CHIP
J 0
(-785 650);
DISPLAY 0.787234 (-785 650);
FORCEPROP 1 LAST PACK_TYPE 0201LF
J 0
(-785 550);
DISPLAY 0.787234 (-785 550);
FORCEPROP 2 LAST CDS_LIB pure_quanta
J 0
(-825 725);
DISPLAY INVISIBLE (-825 725);
FORCEPROP 1 LAST PATH I119
J 0
(-775 900);
DISPLAY 0.978723 (-775 900);
PAINT WHITE (-775 900);
DISPLAY INVISIBLE (-775 900);
FORCEPROP 1 LAST PART_NUMBER CS24701JE04
J 0
(-785 600);
DISPLAY 0.978723 (-785 600);
DISPLAY INVISIBLE (-785 600);
FORCEADD P1V0..1
(-8950 6400);
FORCEPROP 3 LASTPIN (-8950 6350) SIG_NAME P1V8_CPU0_RT_1D\g
J 0
(-8940 6360);
DISPLAY 0.659574 (-8940 6360);
PAINT MONO (-8940 6360);
DISPLAY INVISIBLE (-8940 6360);
FORCEPROP 1 LAST HDL_POWER P1V8_CPU0_RT_1D
J 1
(-8950 6450);
DISPLAY 0.489362 (-8950 6450);
FORCEPROP 2 LAST CDS_LIB pure_quanta_power
J 0
(-8950 6400);
DISPLAY INVISIBLE (-8950 6400);
FORCEPROP 1 LAST PATH I12
J 0
(-8900 6425);
DISPLAY 0.872340 (-8900 6425);
PAINT AQUA (-8900 6425);
DISPLAY INVISIBLE (-8900 6425);
FORCEADD GND..1
(-825 425);
FORCEPROP 3 LASTPIN (-825 475) SIG_NAME GND\g
J 0
(-815 485);
DISPLAY 0.659574 (-815 485);
PAINT MONO (-815 485);
DISPLAY INVISIBLE (-815 485);
FORCEPROP 1 LAST SIZE 1B
J 0
(-750 375);
DISPLAY 0.851064 (-750 375);
PAINT GREEN (-750 375);
DISPLAY INVISIBLE (-750 375);
FORCEPROP 2 LAST BOM_COST MEM
J 0
(-925 500);
DISPLAY 0.808511 (-925 500);
DISPLAY INVISIBLE (-925 500);
FORCEPROP 2 LAST CDS_LIB pure_quanta_power
J 0
(-825 425);
DISPLAY INVISIBLE (-825 425);
FORCEPROP 1 LAST HDL_POWER GND
J 0
(-825 575);
DISPLAY 0.851064 (-825 575);
PAINT GREEN (-825 575);
DISPLAY INVISIBLE (-825 575);
FORCEPROP 1 LAST PATH I120
J 0
(-750 425);
DISPLAY 0.872340 (-750 425);
PAINT AQUA (-750 425);
DISPLAY INVISIBLE (-750 425);
FORCEADD Q_RES..2
(-1100 1350);
FORCEPROP 1 LAST LOCATION R1472
J 0
(-1055 1475);
DISPLAY 0.978723 (-1055 1475);
FORCEPROP 0 LAST $SEC 1
J 0
(-1050 1525);
DISPLAY 0.680851 (-1050 1525);
PAINT MONO (-1050 1525);
DISPLAY INVISIBLE (-1050 1525);
FORCEPROP 0 LAST CDS_SEC 1
J 0
(-1050 1525);
DISPLAY 0.680851 (-1050 1525);
DISPLAY INVISIBLE (-1050 1525);
FORCEPROP 1 LASTPIN (-1100 1450) $PN 1
J 0
(-1095 1412);
DISPLAY 0.787234 (-1095 1412);
PAINT MONO (-1095 1412);
FORCEPROP 1 LASTPIN (-1100 1250) $PN 2
J 0
(-1095 1260);
DISPLAY 0.787234 (-1095 1260);
PAINT MONO (-1095 1260);
FORCEPROP 1 LAST PACK_TYPE 0201LF
J 0
(-1060 1175);
DISPLAY 0.787234 (-1060 1175);
FORCEPROP 1 LAST MATERIAL EMPTY
J 0
(-1060 1275);
DISPLAY 0.787234 (-1060 1275);
PAINT RED (-1060 1275);
FORCEPROP 1 LAST WATTAGE 1/20W
J 0
(-1060 1325);
DISPLAY 0.787234 (-1060 1325);
FORCEPROP 1 LAST TOLERANCE 1%
J 0
(-1055 1375);
DISPLAY 0.787234 (-1055 1375);
FORCEPROP 1 LAST VALUE 1K
J 0
(-1055 1425);
DISPLAY 0.787234 (-1055 1425);
FORCEPROP 2 LAST CDS_LIB pure_quanta
J 0
(-1100 1350);
DISPLAY INVISIBLE (-1100 1350);
FORCEPROP 1 LAST PATH I121
J 0
(-1050 1525);
DISPLAY 0.978723 (-1050 1525);
PAINT WHITE (-1050 1525);
DISPLAY INVISIBLE (-1050 1525);
FORCEPROP 1 LAST PART_NUMBER CS21001FE07
J 0
(-1060 1225);
DISPLAY 0.978723 (-1060 1225);
DISPLAY INVISIBLE (-1060 1225);
FORCEADD Q_RES..2
(-825 1375);
FORCEPROP 1 LAST LOCATION R1473
J 0
(-780 1500);
DISPLAY 0.787234 (-780 1500);
FORCEPROP 0 LAST $SEC 1
J 0
(-775 1550);
DISPLAY 0.680851 (-775 1550);
PAINT MONO (-775 1550);
DISPLAY INVISIBLE (-775 1550);
FORCEPROP 0 LAST CDS_SEC 1
J 0
(-775 1550);
DISPLAY 0.680851 (-775 1550);
DISPLAY INVISIBLE (-775 1550);
FORCEPROP 1 LASTPIN (-825 1475) $PN 1
J 0
(-820 1437);
DISPLAY 0.787234 (-820 1437);
PAINT MONO (-820 1437);
FORCEPROP 1 LASTPIN (-825 1275) $PN 2
J 0
(-820 1285);
DISPLAY 0.787234 (-820 1285);
PAINT MONO (-820 1285);
FORCEPROP 1 LAST PACK_TYPE 0201LF
J 0
(-775 1225);
DISPLAY 0.787234 (-775 1225);
FORCEPROP 1 LAST MATERIAL EMPTY
J 0
(-785 1300);
DISPLAY 0.787234 (-785 1300);
PAINT RED (-785 1300);
FORCEPROP 1 LAST VALUE 4.7K
J 0
(-780 1450);
DISPLAY 0.787234 (-780 1450);
FORCEPROP 1 LAST TOLERANCE 5%
J 0
(-780 1400);
DISPLAY 0.787234 (-780 1400);
FORCEPROP 1 LAST WATTAGE 1/20W
J 0
(-785 1350);
DISPLAY 0.787234 (-785 1350);
FORCEPROP 2 LAST CDS_LIB pure_quanta
J 2
(-825 1375);
DISPLAY INVISIBLE (-825 1375);
FORCEPROP 1 LAST PATH I122
J 0
(-775 1550);
DISPLAY 0.978723 (-775 1550);
PAINT WHITE (-775 1550);
DISPLAY INVISIBLE (-775 1550);
FORCEPROP 1 LAST PART_NUMBER CS24701JE04
J 0
(-785 1250);
DISPLAY 0.978723 (-785 1250);
DISPLAY INVISIBLE (-785 1250);
FORCEADD P1V0..1
(-825 1675);
FORCEPROP 3 LASTPIN (-825 1625) SIG_NAME P1V8_CPU0_RT_1D\g
J 0
(-815 1635);
DISPLAY 0.659574 (-815 1635);
PAINT MONO (-815 1635);
DISPLAY INVISIBLE (-815 1635);
FORCEPROP 1 LAST HDL_POWER P1V8_CPU0_RT_1D
J 1
(-825 1725);
DISPLAY 0.489362 (-825 1725);
PAINT SKYBLUE (-825 1725);
FORCEPROP 2 LAST CDS_LIB pure_quanta_power
J 0
(-825 1675);
DISPLAY INVISIBLE (-825 1675);
FORCEPROP 1 LAST PATH I123
J 0
(-775 1700);
DISPLAY 0.872340 (-775 1700);
PAINT AQUA (-775 1700);
DISPLAY INVISIBLE (-775 1700);
FORCEADD OFFPAGE..1
R 2
(-2725 3650);
FORCEPROP 2 LAST $XR0 288 
J 0
(-2539 3650);
DISPLAY 0.638298 (-2539 3650);
PAINT MONO (-2539 3650);
FORCEPROP 2 LAST CDS_LIB standard
J 0
(-2725 3650);
DISPLAY INVISIBLE (-2725 3650);
FORCEPROP 1 LAST OFFPAGE TRUE
J 2
(-3050 3525);
DISPLAY 0.872340 (-3050 3525);
DISPLAY INVISIBLE (-3050 3525);
FORCEPROP 1 LAST COMMENT_BODY TRUE
J 2
(-2850 3550);
DISPLAY 0.872340 (-2850 3550);
PAINT GREEN (-2850 3550);
DISPLAY INVISIBLE (-2850 3550);
FORCEPROP 2 LAST PATH I124
J 0
(-2550 3725);
DISPLAY 0.680851 (-2550 3725);
DISPLAY INVISIBLE (-2550 3725);
FORCEADD OFFPAGE..1
R 2
(-2725 3550);
FORCEPROP 2 LAST $XR0 288 
J 0
(-2539 3550);
DISPLAY 0.638298 (-2539 3550);
PAINT MONO (-2539 3550);
FORCEPROP 2 LAST CDS_LIB standard
J 0
(-2725 3550);
DISPLAY INVISIBLE (-2725 3550);
FORCEPROP 1 LAST OFFPAGE TRUE
J 2
(-3050 3425);
DISPLAY 0.872340 (-3050 3425);
DISPLAY INVISIBLE (-3050 3425);
FORCEPROP 1 LAST COMMENT_BODY TRUE
J 2
(-2850 3450);
DISPLAY 0.872340 (-2850 3450);
PAINT GREEN (-2850 3450);
DISPLAY INVISIBLE (-2850 3450);
FORCEPROP 2 LAST PATH I125
J 0
(-2550 3625);
DISPLAY 0.680851 (-2550 3625);
DISPLAY INVISIBLE (-2550 3625);
FORCEADD OFFPAGE..1
R 2
(-2725 3450);
FORCEPROP 2 LAST $XR0 288 
J 0
(-2539 3450);
DISPLAY 0.638298 (-2539 3450);
PAINT MONO (-2539 3450);
FORCEPROP 2 LAST CDS_LIB standard
J 0
(-2725 3450);
DISPLAY INVISIBLE (-2725 3450);
FORCEPROP 1 LAST OFFPAGE TRUE
J 2
(-3050 3325);
DISPLAY 0.872340 (-3050 3325);
DISPLAY INVISIBLE (-3050 3325);
FORCEPROP 1 LAST COMMENT_BODY TRUE
J 2
(-2850 3350);
DISPLAY 0.872340 (-2850 3350);
PAINT GREEN (-2850 3350);
DISPLAY INVISIBLE (-2850 3350);
FORCEPROP 2 LAST PATH I126
J 0
(-2550 3525);
DISPLAY 0.680851 (-2550 3525);
DISPLAY INVISIBLE (-2550 3525);
FORCEADD OFFPAGE..1
R 2
(-2750 3350);
FORCEPROP 2 LAST $XR0 288 
J 0
(-2564 3350);
DISPLAY 0.638298 (-2564 3350);
PAINT MONO (-2564 3350);
FORCEPROP 2 LAST CDS_LIB standard
J 0
(-2750 3350);
DISPLAY INVISIBLE (-2750 3350);
FORCEPROP 1 LAST OFFPAGE TRUE
J 2
(-3075 3225);
DISPLAY 0.872340 (-3075 3225);
DISPLAY INVISIBLE (-3075 3225);
FORCEPROP 1 LAST COMMENT_BODY TRUE
J 2
(-2875 3250);
DISPLAY 0.872340 (-2875 3250);
PAINT GREEN (-2875 3250);
DISPLAY INVISIBLE (-2875 3250);
FORCEPROP 2 LAST PATH I127
J 0
(-2575 3425);
DISPLAY 0.680851 (-2575 3425);
DISPLAY INVISIBLE (-2575 3425);
FORCEADD OFFPAGE..3
R 2
(-7800 1550);
FORCEPROP 2 LAST $XR1 186 
J 0
(-8200 1550);
DISPLAY 0.638298 (-8200 1550);
PAINT MONO (-8200 1550);
FORCEPROP 2 LAST $XR0 185 
J 0
(-8080 1550);
DISPLAY 0.638298 (-8080 1550);
PAINT MONO (-8080 1550);
FORCEPROP 2 LAST CDS_LIB standard
J 0
(-7800 1550);
DISPLAY INVISIBLE (-7800 1550);
FORCEPROP 1 LAST OFFPAGE TRUE
J 2
(-8125 1425);
DISPLAY 0.872340 (-8125 1425);
PAINT GREEN (-8125 1425);
DISPLAY INVISIBLE (-8125 1425);
FORCEPROP 1 LAST COMMENT_BODY TRUE
J 2
(-7750 1450);
DISPLAY 0.872340 (-7750 1450);
PAINT GREEN (-7750 1450);
DISPLAY INVISIBLE (-7750 1450);
FORCEPROP 2 LAST PATH I13
J 0
(-8075 1600);
DISPLAY 0.680851 (-8075 1600);
DISPLAY INVISIBLE (-8075 1600);
FORCEADD OFFPAGE..5
(-7825 1650);
FORCEPROP 2 LAST $XR1 186 
J 0
(-8200 1650);
DISPLAY 0.638298 (-8200 1650);
PAINT MONO (-8200 1650);
FORCEPROP 2 LAST $XR0 185 
J 0
(-8080 1650);
DISPLAY 0.638298 (-8080 1650);
PAINT MONO (-8080 1650);
FORCEPROP 2 LAST CDS_LIB standard
J 0
(-7825 1650);
DISPLAY INVISIBLE (-7825 1650);
FORCEPROP 1 LAST OFFPAGE TRUE
J 0
(-7500 1525);
DISPLAY 0.872340 (-7500 1525);
PAINT GREEN (-7500 1525);
DISPLAY INVISIBLE (-7500 1525);
FORCEPROP 1 LAST COMMENT_BODY TRUE
J 0
(-7725 1575);
DISPLAY 0.872340 (-7725 1575);
PAINT GREEN (-7725 1575);
DISPLAY INVISIBLE (-7725 1575);
FORCEPROP 2 LAST PATH I14
J 0
(-8075 1700);
DISPLAY 0.680851 (-8075 1700);
DISPLAY INVISIBLE (-8075 1700);
FORCEADD Q_RES..1
(-6600 1050);
FORCEPROP 1 LAST LOCATION R612
J 0
(-6850 1050);
DISPLAY 0.978723 (-6850 1050);
FORCEPROP 2 LAST SEC 1
J 0
(-6650 1250);
DISPLAY 0.680851 (-6650 1250);
PAINT MONO (-6650 1250);
DISPLAY INVISIBLE (-6650 1250);
FORCEPROP 1 LASTPIN (-6700 1050) $PN 1
J 0
(-6688 1062);
DISPLAY 0.787234 (-6688 1062);
PAINT MONO (-6688 1062);
FORCEPROP 1 LASTPIN (-6500 1050) $PN 2
J 0
(-6538 1062);
DISPLAY 0.787234 (-6538 1062);
PAINT MONO (-6538 1062);
FORCEPROP 1 LAST PACK_TYPE 0201LF
J 0
(-6575 1125);
DISPLAY 0.787234 (-6575 1125);
FORCEPROP 1 LAST MATERIAL CHIP
J 0
(-6775 1125);
DISPLAY 0.787234 (-6775 1125);
FORCEPROP 2 LAST CDS_LIB pure_quanta
J 0
(-6600 1050);
DISPLAY INVISIBLE (-6600 1050);
FORCEPROP 1 LAST TOLERANCE 5%
J 0
(-6775 1175);
DISPLAY 0.787234 (-6775 1175);
DISPLAY INVISIBLE (-6775 1175);
FORCEPROP 1 LAST VALUE 0
J 2
(-6800 1175);
DISPLAY 0.787234 (-6800 1175);
DISPLAY INVISIBLE (-6800 1175);
FORCEPROP 1 LAST WATTAGE 1/20W
J 2
(-6800 1125);
DISPLAY 0.787234 (-6800 1125);
DISPLAY INVISIBLE (-6800 1125);
FORCEPROP 2 LAST SEC_TYPE 0201LF
J 0
(-6650 1250);
DISPLAY 0.680851 (-6650 1250);
DISPLAY INVISIBLE (-6650 1250);
FORCEPROP 1 LAST PATH I15
J 0
(-6650 1200);
DISPLAY 0.978723 (-6650 1200);
PAINT WHITE (-6650 1200);
DISPLAY INVISIBLE (-6650 1200);
FORCEPROP 1 LAST PART_NUMBER CS00001JE10
J 0
(-6650 1175);
DISPLAY 0.808511 (-6650 1175);
DISPLAY INVISIBLE (-6650 1175);
FORCEADD UNIVERSAL_GND..1
(-6300 400);
FORCEPROP 3 LASTPIN (-6300 450) SIG_NAME GND\g
J 0
(-6290 460);
DISPLAY 0.659574 (-6290 460);
PAINT MONO (-6290 460);
DISPLAY INVISIBLE (-6290 460);
FORCEPROP 2 LAST CDS_LIB pure_quanta_power
J 0
(-6300 400);
DISPLAY INVISIBLE (-6300 400);
FORCEPROP 1 LAST HDL_POWER GND
J 1
(-6275 325);
DISPLAY 0.872340 (-6275 325);
PAINT GREEN (-6275 325);
DISPLAY INVISIBLE (-6275 325);
FORCEPROP 1 LAST PATH I16
J 0
(-6225 400);
DISPLAY 0.872340 (-6225 400);
PAINT AQUA (-6225 400);
DISPLAY INVISIBLE (-6225 400);
FORCEADD UNIVERSAL_GND..1
(-6150 400);
FORCEPROP 3 LASTPIN (-6150 450) SIG_NAME GND\g
J 0
(-6140 460);
DISPLAY 0.659574 (-6140 460);
PAINT MONO (-6140 460);
DISPLAY INVISIBLE (-6140 460);
FORCEPROP 2 LAST CDS_LIB pure_quanta_power
J 0
(-6150 400);
DISPLAY INVISIBLE (-6150 400);
FORCEPROP 1 LAST HDL_POWER GND
J 1
(-6125 325);
DISPLAY 0.872340 (-6125 325);
PAINT GREEN (-6125 325);
DISPLAY INVISIBLE (-6125 325);
FORCEPROP 1 LAST PATH I17
J 0
(-6075 400);
DISPLAY 0.872340 (-6075 400);
PAINT AQUA (-6075 400);
DISPLAY INVISIBLE (-6075 400);
FORCEADD Q_RES..2
R 2
(-6300 725);
FORCEPROP 1 LAST LOCATION R629
J 2
(-6345 850);
DISPLAY 0.978723 (-6345 850);
FORCEPROP 0 LAST $SEC 1
J 0
(-6325 900);
DISPLAY 0.680851 (-6325 900);
PAINT MONO (-6325 900);
DISPLAY INVISIBLE (-6325 900);
FORCEPROP 0 LAST CDS_SEC 1
J 0
(-6325 900);
DISPLAY 0.680851 (-6325 900);
DISPLAY INVISIBLE (-6325 900);
FORCEPROP 1 LASTPIN (-6300 825) $PN 1
J 2
(-6305 787);
DISPLAY 0.787234 (-6305 787);
PAINT MONO (-6305 787);
FORCEPROP 1 LASTPIN (-6300 625) $PN 2
J 2
(-6305 635);
DISPLAY 0.787234 (-6305 635);
PAINT MONO (-6305 635);
FORCEPROP 1 LAST MATERIAL EMPTY
J 2
(-6340 650);
DISPLAY 0.978723 (-6340 650);
FORCEPROP 1 LAST PACK_TYPE 0201LF
J 2
(-6340 550);
DISPLAY 0.978723 (-6340 550);
FORCEPROP 1 LAST TOLERANCE 1%
J 2
(-6345 750);
DISPLAY 0.978723 (-6345 750);
FORCEPROP 1 LAST VALUE 51.1
J 2
(-6345 800);
DISPLAY 0.978723 (-6345 800);
FORCEPROP 1 LAST WATTAGE 1/20W
J 2
(-6340 700);
DISPLAY 0.978723 (-6340 700);
FORCEPROP 2 LAST CDS_LIB pure_quanta
J 0
(-6300 725);
DISPLAY INVISIBLE (-6300 725);
FORCEPROP 1 LAST PATH I18
J 2
(-6350 900);
DISPLAY 0.978723 (-6350 900);
PAINT WHITE (-6350 900);
DISPLAY INVISIBLE (-6350 900);
FORCEPROP 1 LAST PART_NUMBER CS05111FE00
J 2
(-6340 600);
DISPLAY 0.978723 (-6340 600);
DISPLAY INVISIBLE (-6340 600);
FORCEADD Q_RES..2
(-6150 725);
FORCEPROP 1 LAST LOCATION R630
J 0
(-6105 850);
DISPLAY 0.978723 (-6105 850);
FORCEPROP 0 LAST $SEC 1
J 0
(-6100 900);
DISPLAY 0.680851 (-6100 900);
PAINT MONO (-6100 900);
DISPLAY INVISIBLE (-6100 900);
FORCEPROP 0 LAST CDS_SEC 1
J 0
(-6100 900);
DISPLAY 0.680851 (-6100 900);
DISPLAY INVISIBLE (-6100 900);
FORCEPROP 1 LASTPIN (-6150 825) $PN 1
J 0
(-6145 787);
DISPLAY 0.787234 (-6145 787);
PAINT MONO (-6145 787);
FORCEPROP 1 LASTPIN (-6150 625) $PN 2
J 0
(-6145 635);
DISPLAY 0.787234 (-6145 635);
PAINT MONO (-6145 635);
FORCEPROP 1 LAST PACK_TYPE 0201LF
J 0
(-6110 550);
DISPLAY 0.978723 (-6110 550);
FORCEPROP 1 LAST MATERIAL EMPTY
J 0
(-6110 650);
DISPLAY 0.978723 (-6110 650);
FORCEPROP 1 LAST WATTAGE 1/20W
J 0
(-6110 700);
DISPLAY 0.978723 (-6110 700);
FORCEPROP 1 LAST TOLERANCE 1%
J 0
(-6105 750);
DISPLAY 0.978723 (-6105 750);
FORCEPROP 1 LAST VALUE 51.1
J 0
(-6105 800);
DISPLAY 0.978723 (-6105 800);
FORCEPROP 2 LAST CDS_LIB pure_quanta
J 0
(-6150 725);
DISPLAY INVISIBLE (-6150 725);
FORCEPROP 1 LAST PATH I19
J 0
(-6100 900);
DISPLAY 0.978723 (-6100 900);
PAINT WHITE (-6100 900);
DISPLAY INVISIBLE (-6100 900);
FORCEPROP 1 LAST PART_NUMBER CS05111FE00
J 0
(-6110 600);
DISPLAY 0.978723 (-6110 600);
DISPLAY INVISIBLE (-6110 600);
FORCEADD OFFPAGE..1
(-8050 1050);
FORCEPROP 2 LAST $XR0 182 
J 0
(-8332 1050);
DISPLAY 0.638298 (-8332 1050);
PAINT MONO (-8332 1050);
FORCEPROP 2 LAST CDS_LIB standard
J 0
(-8050 1050);
DISPLAY INVISIBLE (-8050 1050);
FORCEPROP 1 LAST OFFPAGE TRUE
J 0
(-7725 925);
DISPLAY 0.872340 (-7725 925);
DISPLAY INVISIBLE (-7725 925);
FORCEPROP 1 LAST COMMENT_BODY TRUE
J 0
(-7925 950);
DISPLAY 0.872340 (-7925 950);
PAINT GREEN (-7925 950);
DISPLAY INVISIBLE (-7925 950);
FORCEPROP 2 LAST PATH I2
J 0
(-8325 1100);
DISPLAY 0.680851 (-8325 1100);
DISPLAY INVISIBLE (-8325 1100);
FORCEADD Q_RES..1
(-6600 1200);
FORCEPROP 1 LAST LOCATION R611
J 0
(-6850 1200);
DISPLAY 0.978723 (-6850 1200);
FORCEPROP 2 LAST SEC 1
J 0
(-6650 1400);
DISPLAY 0.680851 (-6650 1400);
PAINT MONO (-6650 1400);
DISPLAY INVISIBLE (-6650 1400);
FORCEPROP 1 LASTPIN (-6700 1200) $PN 1
J 0
(-6688 1212);
DISPLAY 0.787234 (-6688 1212);
PAINT MONO (-6688 1212);
FORCEPROP 1 LASTPIN (-6500 1200) $PN 2
J 0
(-6538 1212);
DISPLAY 0.787234 (-6538 1212);
PAINT MONO (-6538 1212);
FORCEPROP 1 LAST TOLERANCE 5%
J 0
(-6775 1325);
DISPLAY 0.787234 (-6775 1325);
FORCEPROP 1 LAST VALUE 0
J 2
(-6800 1325);
DISPLAY 0.787234 (-6800 1325);
FORCEPROP 1 LAST WATTAGE 1/20W
J 2
(-6800 1275);
DISPLAY 0.787234 (-6800 1275);
FORCEPROP 1 LAST PACK_TYPE 0201LF
J 0
(-6575 1275);
DISPLAY 0.787234 (-6575 1275);
FORCEPROP 1 LAST MATERIAL CHIP
J 0
(-6775 1275);
DISPLAY 0.787234 (-6775 1275);
FORCEPROP 2 LAST CDS_LIB pure_quanta
J 0
(-6600 1200);
DISPLAY INVISIBLE (-6600 1200);
FORCEPROP 0 LAST SEC_TYPE 0201LF
J 0
(-6650 1400);
DISPLAY 0.680851 (-6650 1400);
DISPLAY INVISIBLE (-6650 1400);
FORCEPROP 1 LAST PATH I20
J 0
(-6650 1350);
DISPLAY 0.978723 (-6650 1350);
PAINT WHITE (-6650 1350);
DISPLAY INVISIBLE (-6650 1350);
FORCEPROP 1 LAST PART_NUMBER CS00001JE10
J 0
(-6650 1325);
DISPLAY 0.808511 (-6650 1325);
DISPLAY INVISIBLE (-6650 1325);
FORCEADD Q_RES..1
(-6325 1550);
FORCEPROP 1 LAST LOCATION R677
J 0
(-6575 1575);
DISPLAY 0.978723 (-6575 1575);
FORCEPROP 0 LAST $SEC 1
J 0
(-6475 1625);
DISPLAY 0.680851 (-6475 1625);
PAINT MONO (-6475 1625);
DISPLAY INVISIBLE (-6475 1625);
FORCEPROP 0 LAST CDS_SEC 1
J 0
(-6475 1625);
DISPLAY 0.680851 (-6475 1625);
DISPLAY INVISIBLE (-6475 1625);
FORCEPROP 1 LASTPIN (-6425 1550) $PN 1
J 0
(-6413 1562);
DISPLAY 0.787234 (-6413 1562);
PAINT MONO (-6413 1562);
FORCEPROP 1 LASTPIN (-6225 1550) $PN 2
J 0
(-6263 1562);
DISPLAY 0.787234 (-6263 1562);
PAINT MONO (-6263 1562);
FORCEPROP 2 LAST CDS_LIB pure_quanta
J 0
(-6325 1550);
DISPLAY INVISIBLE (-6325 1550);
FORCEPROP 1 LAST MATERIAL CHIP
J 0
(-6500 1625);
DISPLAY 0.787234 (-6500 1625);
DISPLAY INVISIBLE (-6500 1625);
FORCEPROP 1 LAST WATTAGE 1/20W
J 2
(-6525 1625);
DISPLAY 0.787234 (-6525 1625);
DISPLAY INVISIBLE (-6525 1625);
FORCEPROP 1 LAST PACK_TYPE 0201LF
J 0
(-6300 1625);
DISPLAY 0.787234 (-6300 1625);
DISPLAY INVISIBLE (-6300 1625);
FORCEPROP 1 LAST VALUE 49.9
J 2
(-6525 1675);
DISPLAY 0.787234 (-6525 1675);
DISPLAY INVISIBLE (-6525 1675);
FORCEPROP 1 LAST TOLERANCE 1%
J 0
(-6500 1675);
DISPLAY 0.787234 (-6500 1675);
DISPLAY INVISIBLE (-6500 1675);
FORCEPROP 1 LAST PATH I21
J 0
(-6375 1700);
DISPLAY 0.978723 (-6375 1700);
PAINT WHITE (-6375 1700);
DISPLAY INVISIBLE (-6375 1700);
FORCEPROP 1 LAST PART_NUMBER CS04991FE06
J 0
(-6375 1675);
DISPLAY 0.808511 (-6375 1675);
DISPLAY INVISIBLE (-6375 1675);
FORCEADD Q_RES..1
(-6325 1650);
FORCEPROP 1 LAST LOCATION R676
J 0
(-6575 1675);
DISPLAY 0.978723 (-6575 1675);
FORCEPROP 0 LAST $SEC 1
J 0
(-6375 1825);
DISPLAY 0.680851 (-6375 1825);
PAINT MONO (-6375 1825);
DISPLAY INVISIBLE (-6375 1825);
FORCEPROP 0 LAST CDS_SEC 1
J 0
(-6375 1825);
DISPLAY 0.680851 (-6375 1825);
DISPLAY INVISIBLE (-6375 1825);
FORCEPROP 1 LASTPIN (-6425 1650) $PN 1
J 0
(-6413 1662);
DISPLAY 0.787234 (-6413 1662);
PAINT MONO (-6413 1662);
FORCEPROP 1 LASTPIN (-6225 1650) $PN 2
J 0
(-6263 1662);
DISPLAY 0.787234 (-6263 1662);
PAINT MONO (-6263 1662);
FORCEPROP 1 LAST PACK_TYPE 0201LF
J 0
(-6300 1725);
DISPLAY 0.787234 (-6300 1725);
FORCEPROP 1 LAST WATTAGE 1/20W
J 2
(-6525 1725);
DISPLAY 0.787234 (-6525 1725);
FORCEPROP 1 LAST MATERIAL CHIP
J 0
(-6500 1725);
DISPLAY 0.787234 (-6500 1725);
FORCEPROP 1 LAST VALUE 49.9
J 2
(-6525 1775);
DISPLAY 0.787234 (-6525 1775);
FORCEPROP 1 LAST TOLERANCE 1%
J 0
(-6500 1775);
DISPLAY 0.787234 (-6500 1775);
FORCEPROP 2 LAST CDS_LIB pure_quanta
J 0
(-6325 1650);
DISPLAY INVISIBLE (-6325 1650);
FORCEPROP 1 LAST PATH I22
J 0
(-6375 1800);
DISPLAY 0.978723 (-6375 1800);
PAINT WHITE (-6375 1800);
DISPLAY INVISIBLE (-6375 1800);
FORCEPROP 1 LAST PART_NUMBER CS04991FE06
J 0
(-6375 1775);
DISPLAY 0.808511 (-6375 1775);
DISPLAY INVISIBLE (-6375 1775);
FORCEADD OFFPAGE..1
(-6150 2050);
FORCEPROP 2 LAST $XR0 288 
J 0
(-6402 2050);
DISPLAY 0.638298 (-6402 2050);
PAINT MONO (-6402 2050);
FORCEPROP 2 LAST CDS_LIB standard
J 0
(-6150 2050);
DISPLAY INVISIBLE (-6150 2050);
FORCEPROP 1 LAST OFFPAGE TRUE
J 0
(-5825 1925);
DISPLAY 0.872340 (-5825 1925);
DISPLAY INVISIBLE (-5825 1925);
FORCEPROP 1 LAST COMMENT_BODY TRUE
J 0
(-6025 1950);
DISPLAY 0.872340 (-6025 1950);
PAINT GREEN (-6025 1950);
DISPLAY INVISIBLE (-6025 1950);
FORCEPROP 2 LAST PATH I23
J 0
(-6400 2100);
DISPLAY 0.680851 (-6400 2100);
DISPLAY INVISIBLE (-6400 2100);
FORCEADD OFFPAGE..1
(-6150 1950);
FORCEPROP 2 LAST $XR0 288 
J 0
(-6402 1950);
DISPLAY 0.638298 (-6402 1950);
PAINT MONO (-6402 1950);
FORCEPROP 2 LAST CDS_LIB standard
J 0
(-6150 1950);
DISPLAY INVISIBLE (-6150 1950);
FORCEPROP 1 LAST OFFPAGE TRUE
J 0
(-5825 1825);
DISPLAY 0.872340 (-5825 1825);
DISPLAY INVISIBLE (-5825 1825);
FORCEPROP 1 LAST COMMENT_BODY TRUE
J 0
(-6025 1850);
DISPLAY 0.872340 (-6025 1850);
PAINT GREEN (-6025 1850);
DISPLAY INVISIBLE (-6025 1850);
FORCEPROP 2 LAST PATH I24
J 0
(-6400 2000);
DISPLAY 0.680851 (-6400 2000);
DISPLAY INVISIBLE (-6400 2000);
FORCEADD OFFPAGE..3
R 2
(-7650 2800);
FORCEPROP 2 LAST $XR0 184 
J 0
(-7930 2800);
DISPLAY 0.638298 (-7930 2800);
PAINT MONO (-7930 2800);
FORCEPROP 2 LAST CDS_LIB standard
J 0
(-7650 2800);
DISPLAY INVISIBLE (-7650 2800);
FORCEPROP 1 LAST OFFPAGE TRUE
J 2
(-7975 2675);
DISPLAY 0.872340 (-7975 2675);
PAINT GREEN (-7975 2675);
DISPLAY INVISIBLE (-7975 2675);
FORCEPROP 1 LAST COMMENT_BODY TRUE
J 2
(-7600 2700);
DISPLAY 0.872340 (-7600 2700);
PAINT GREEN (-7600 2700);
DISPLAY INVISIBLE (-7600 2700);
FORCEPROP 2 LAST PATH I25
J 0
(-7925 2850);
DISPLAY 0.680851 (-7925 2850);
DISPLAY INVISIBLE (-7925 2850);
FORCEADD OFFPAGE..1
(-7650 2900);
FORCEPROP 2 LAST $XR0 184 
J 0
(-7902 2900);
DISPLAY 0.638298 (-7902 2900);
PAINT MONO (-7902 2900);
FORCEPROP 2 LAST CDS_LIB standard
J 0
(-7650 2900);
DISPLAY INVISIBLE (-7650 2900);
FORCEPROP 1 LAST OFFPAGE TRUE
J 0
(-7325 2775);
DISPLAY 0.872340 (-7325 2775);
DISPLAY INVISIBLE (-7325 2775);
FORCEPROP 1 LAST COMMENT_BODY TRUE
J 0
(-7525 2800);
DISPLAY 0.872340 (-7525 2800);
PAINT GREEN (-7525 2800);
DISPLAY INVISIBLE (-7525 2800);
FORCEPROP 2 LAST PATH I26
J 0
(-7900 2950);
DISPLAY 0.680851 (-7900 2950);
DISPLAY INVISIBLE (-7900 2950);
FORCEADD OFFPAGE..5
R 2
(-7800 3900);
FORCEPROP 2 LAST $XR0 288 
J 0
(-7611 3900);
DISPLAY 0.638298 (-7611 3900);
PAINT MONO (-7611 3900);
FORCEPROP 2 LAST CDS_LIB standard
J 0
(-7800 3900);
DISPLAY INVISIBLE (-7800 3900);
FORCEPROP 1 LAST OFFPAGE TRUE
J 2
(-8125 3775);
DISPLAY 0.872340 (-8125 3775);
PAINT GREEN (-8125 3775);
DISPLAY INVISIBLE (-8125 3775);
FORCEPROP 1 LAST COMMENT_BODY TRUE
J 2
(-7900 3825);
DISPLAY 0.872340 (-7900 3825);
PAINT GREEN (-7900 3825);
DISPLAY INVISIBLE (-7900 3825);
FORCEPROP 2 LAST PATH I27
J 0
(-7600 3950);
DISPLAY 0.680851 (-7600 3950);
DISPLAY INVISIBLE (-7600 3950);
FORCEADD OFFPAGE..1
(-6150 2150);
FORCEPROP 2 LAST $XR0 288 
J 0
(-6402 2150);
DISPLAY 0.638298 (-6402 2150);
PAINT MONO (-6402 2150);
FORCEPROP 2 LAST CDS_LIB standard
J 0
(-6150 2150);
DISPLAY INVISIBLE (-6150 2150);
FORCEPROP 1 LAST OFFPAGE TRUE
J 0
(-5825 2025);
DISPLAY 0.872340 (-5825 2025);
DISPLAY INVISIBLE (-5825 2025);
FORCEPROP 1 LAST COMMENT_BODY TRUE
J 0
(-6025 2050);
DISPLAY 0.872340 (-6025 2050);
PAINT GREEN (-6025 2050);
DISPLAY INVISIBLE (-6025 2050);
FORCEPROP 2 LAST PATH I28
J 0
(-6400 2200);
DISPLAY 0.680851 (-6400 2200);
DISPLAY INVISIBLE (-6400 2200);
FORCEADD Q_RES..1
(-6350 2800);
FORCEPROP 1 LAST LOCATION R1026
J 0
(-6600 2825);
DISPLAY 0.978723 (-6600 2825);
FORCEPROP 0 LAST $SEC 1
J 0
(-6600 2875);
DISPLAY 0.680851 (-6600 2875);
PAINT MONO (-6600 2875);
DISPLAY INVISIBLE (-6600 2875);
FORCEPROP 0 LAST CDS_SEC 1
J 0
(-6600 2875);
DISPLAY 0.680851 (-6600 2875);
DISPLAY INVISIBLE (-6600 2875);
FORCEPROP 1 LASTPIN (-6450 2800) $PN 1
J 0
(-6438 2812);
DISPLAY 0.787234 (-6438 2812);
PAINT MONO (-6438 2812);
FORCEPROP 1 LASTPIN (-6250 2800) $PN 2
J 0
(-6288 2812);
DISPLAY 0.787234 (-6288 2812);
PAINT MONO (-6288 2812);
FORCEPROP 2 LAST CDS_LIB pure_quanta
J 0
(-6350 2800);
DISPLAY INVISIBLE (-6350 2800);
FORCEPROP 1 LAST PACK_TYPE 0201LF
J 0
(-6325 2875);
DISPLAY 0.787234 (-6325 2875);
DISPLAY INVISIBLE (-6325 2875);
FORCEPROP 1 LAST MATERIAL CHIP
J 0
(-6525 2875);
DISPLAY 0.787234 (-6525 2875);
DISPLAY INVISIBLE (-6525 2875);
FORCEPROP 1 LAST TOLERANCE 5%
J 0
(-6525 2925);
DISPLAY 0.787234 (-6525 2925);
DISPLAY INVISIBLE (-6525 2925);
FORCEPROP 1 LAST VALUE 0
J 2
(-6550 2925);
DISPLAY 0.787234 (-6550 2925);
DISPLAY INVISIBLE (-6550 2925);
FORCEPROP 1 LAST WATTAGE 1/20W
J 2
(-6550 2875);
DISPLAY 0.787234 (-6550 2875);
DISPLAY INVISIBLE (-6550 2875);
FORCEPROP 1 LAST PATH I29
J 0
(-6400 2950);
DISPLAY 0.978723 (-6400 2950);
PAINT WHITE (-6400 2950);
DISPLAY INVISIBLE (-6400 2950);
FORCEPROP 1 LAST PART_NUMBER CS00001JE10
J 0
(-6400 2925);
DISPLAY 0.808511 (-6400 2925);
DISPLAY INVISIBLE (-6400 2925);
FORCEADD UNIVERSAL_GND..1
(-8975 3175);
FORCEPROP 3 LASTPIN (-8975 3225) SIG_NAME GND\g
J 0
(-8965 3235);
DISPLAY 0.659574 (-8965 3235);
PAINT MONO (-8965 3235);
DISPLAY INVISIBLE (-8965 3235);
FORCEPROP 2 LAST CDS_LIB pure_quanta_power
J 0
(-8975 3175);
DISPLAY INVISIBLE (-8975 3175);
FORCEPROP 1 LAST HDL_POWER GND
J 1
(-8950 3100);
DISPLAY 0.872340 (-8950 3100);
PAINT GREEN (-8950 3100);
DISPLAY INVISIBLE (-8950 3100);
FORCEPROP 1 LAST PATH I3
J 0
(-8900 3175);
DISPLAY 0.872340 (-8900 3175);
PAINT AQUA (-8900 3175);
DISPLAY INVISIBLE (-8900 3175);
FORCEADD Q_RES..1
(-6350 2900);
FORCEPROP 1 LAST LOCATION R1025
J 0
(-6600 2925);
DISPLAY 0.978723 (-6600 2925);
FORCEPROP 0 LAST $SEC 1
J 0
(-6400 3075);
DISPLAY 0.680851 (-6400 3075);
PAINT MONO (-6400 3075);
DISPLAY INVISIBLE (-6400 3075);
FORCEPROP 0 LAST CDS_SEC 1
J 0
(-6400 3075);
DISPLAY 0.680851 (-6400 3075);
DISPLAY INVISIBLE (-6400 3075);
FORCEPROP 1 LASTPIN (-6450 2900) $PN 1
J 0
(-6438 2912);
DISPLAY 0.787234 (-6438 2912);
PAINT MONO (-6438 2912);
FORCEPROP 1 LASTPIN (-6250 2900) $PN 2
J 0
(-6288 2912);
DISPLAY 0.787234 (-6288 2912);
PAINT MONO (-6288 2912);
FORCEPROP 1 LAST MATERIAL CHIP
J 0
(-6525 2975);
DISPLAY 0.787234 (-6525 2975);
FORCEPROP 1 LAST PACK_TYPE 0201LF
J 0
(-6325 2975);
DISPLAY 0.787234 (-6325 2975);
FORCEPROP 1 LAST WATTAGE 1/20W
J 2
(-6550 2975);
DISPLAY 0.787234 (-6550 2975);
FORCEPROP 1 LAST TOLERANCE 5%
J 0
(-6525 3025);
DISPLAY 0.787234 (-6525 3025);
FORCEPROP 1 LAST VALUE 0
J 2
(-6550 3025);
DISPLAY 0.787234 (-6550 3025);
FORCEPROP 2 LAST CDS_LIB pure_quanta
J 0
(-6350 2900);
DISPLAY INVISIBLE (-6350 2900);
FORCEPROP 1 LAST PATH I30
J 0
(-6400 3050);
DISPLAY 0.978723 (-6400 3050);
PAINT WHITE (-6400 3050);
DISPLAY INVISIBLE (-6400 3050);
FORCEPROP 1 LAST PART_NUMBER CS00001JE10
J 0
(-6400 3025);
DISPLAY 0.808511 (-6400 3025);
DISPLAY INVISIBLE (-6400 3025);
FORCEADD OFFPAGE..1
(-6025 3250);
FORCEPROP 2 LAST $XR0 288 
J 0
(-6307 3250);
DISPLAY 0.638298 (-6307 3250);
PAINT MONO (-6307 3250);
FORCEPROP 2 LAST CDS_LIB standard
J 0
(-6025 3250);
DISPLAY INVISIBLE (-6025 3250);
FORCEPROP 1 LAST OFFPAGE TRUE
J 0
(-5700 3125);
DISPLAY 0.872340 (-5700 3125);
DISPLAY INVISIBLE (-5700 3125);
FORCEPROP 1 LAST COMMENT_BODY TRUE
J 0
(-5900 3150);
DISPLAY 0.872340 (-5900 3150);
PAINT GREEN (-5900 3150);
DISPLAY INVISIBLE (-5900 3150);
FORCEPROP 2 LAST PATH I31
J 0
(-6300 3300);
DISPLAY 0.680851 (-6300 3300);
DISPLAY INVISIBLE (-6300 3300);
FORCEADD OFFPAGE..1
(-6025 3350);
FORCEPROP 2 LAST $XR0 288 
J 0
(-6307 3350);
DISPLAY 0.638298 (-6307 3350);
PAINT MONO (-6307 3350);
FORCEPROP 2 LAST CDS_LIB standard
J 0
(-6025 3350);
DISPLAY INVISIBLE (-6025 3350);
FORCEPROP 1 LAST OFFPAGE TRUE
J 0
(-5700 3225);
DISPLAY 0.872340 (-5700 3225);
DISPLAY INVISIBLE (-5700 3225);
FORCEPROP 1 LAST COMMENT_BODY TRUE
J 0
(-5900 3250);
DISPLAY 0.872340 (-5900 3250);
PAINT GREEN (-5900 3250);
DISPLAY INVISIBLE (-5900 3250);
FORCEPROP 2 LAST PATH I32
J 0
(-6300 3400);
DISPLAY 0.680851 (-6300 3400);
DISPLAY INVISIBLE (-6300 3400);
FORCEADD OFFPAGE..1
(-5975 2550);
FORCEPROP 2 LAST $XR0 288 
J 0
(-6227 2550);
DISPLAY 0.638298 (-6227 2550);
PAINT MONO (-6227 2550);
FORCEPROP 2 LAST CDS_LIB standard
J 0
(-5975 2550);
DISPLAY INVISIBLE (-5975 2550);
FORCEPROP 1 LAST OFFPAGE TRUE
J 0
(-5650 2425);
DISPLAY 0.872340 (-5650 2425);
DISPLAY INVISIBLE (-5650 2425);
FORCEPROP 1 LAST COMMENT_BODY TRUE
J 0
(-5850 2450);
DISPLAY 0.872340 (-5850 2450);
PAINT GREEN (-5850 2450);
DISPLAY INVISIBLE (-5850 2450);
FORCEPROP 2 LAST PATH I33
J 0
(-6225 2600);
DISPLAY 0.680851 (-6225 2600);
DISPLAY INVISIBLE (-6225 2600);
FORCEADD OFFPAGE..1
(-5975 2450);
FORCEPROP 2 LAST $XR0 288 
J 0
(-6227 2450);
DISPLAY 0.638298 (-6227 2450);
PAINT MONO (-6227 2450);
FORCEPROP 2 LAST CDS_LIB standard
J 0
(-5975 2450);
DISPLAY INVISIBLE (-5975 2450);
FORCEPROP 1 LAST OFFPAGE TRUE
J 0
(-5650 2325);
DISPLAY 0.872340 (-5650 2325);
DISPLAY INVISIBLE (-5650 2325);
FORCEPROP 1 LAST COMMENT_BODY TRUE
J 0
(-5850 2350);
DISPLAY 0.872340 (-5850 2350);
PAINT GREEN (-5850 2350);
DISPLAY INVISIBLE (-5850 2350);
FORCEPROP 2 LAST PATH I34
J 0
(-6225 2500);
DISPLAY 0.680851 (-6225 2500);
DISPLAY INVISIBLE (-6225 2500);
FORCEADD OFFPAGE..1
(-5975 2650);
FORCEPROP 2 LAST $XR0 288 
J 0
(-6227 2650);
DISPLAY 0.638298 (-6227 2650);
PAINT MONO (-6227 2650);
FORCEPROP 2 LAST CDS_LIB standard
J 0
(-5975 2650);
DISPLAY INVISIBLE (-5975 2650);
FORCEPROP 1 LAST OFFPAGE TRUE
J 0
(-5650 2525);
DISPLAY 0.872340 (-5650 2525);
DISPLAY INVISIBLE (-5650 2525);
FORCEPROP 1 LAST COMMENT_BODY TRUE
J 0
(-5850 2550);
DISPLAY 0.872340 (-5850 2550);
PAINT GREEN (-5850 2550);
DISPLAY INVISIBLE (-5850 2550);
FORCEPROP 2 LAST PATH I35
J 0
(-6225 2700);
DISPLAY 0.680851 (-6225 2700);
DISPLAY INVISIBLE (-6225 2700);
FORCEADD Q_RES..2
(-8025 5025);
FORCEPROP 1 LAST LOCATION R1033
J 0
(-7980 5150);
DISPLAY 0.787234 (-7980 5150);
FORCEPROP 0 LAST $SEC 1
J 0
(-7975 5200);
DISPLAY 0.680851 (-7975 5200);
PAINT MONO (-7975 5200);
DISPLAY INVISIBLE (-7975 5200);
FORCEPROP 0 LAST CDS_SEC 1
J 0
(-7975 5200);
DISPLAY 0.680851 (-7975 5200);
DISPLAY INVISIBLE (-7975 5200);
FORCEPROP 1 LASTPIN (-8025 5125) $PN 1
J 0
(-8020 5087);
DISPLAY 0.787234 (-8020 5087);
PAINT MONO (-8020 5087);
FORCEPROP 1 LASTPIN (-8025 4925) $PN 2
J 0
(-8020 4935);
DISPLAY 0.787234 (-8020 4935);
PAINT MONO (-8020 4935);
FORCEPROP 1 LAST TOLERANCE 5%
J 0
(-7980 5050);
DISPLAY 0.787234 (-7980 5050);
FORCEPROP 1 LAST PACK_TYPE 0201LF
J 0
(-7985 4850);
DISPLAY 0.787234 (-7985 4850);
FORCEPROP 1 LAST MATERIAL CHIP
J 0
(-7985 4950);
DISPLAY 0.787234 (-7985 4950);
FORCEPROP 1 LAST WATTAGE 1/20W
J 0
(-7985 5000);
DISPLAY 0.787234 (-7985 5000);
FORCEPROP 1 LAST VALUE 4.7K
J 0
(-7980 5100);
DISPLAY 0.787234 (-7980 5100);
FORCEPROP 2 LAST CDS_LIB pure_quanta
J 0
(-8025 5025);
DISPLAY INVISIBLE (-8025 5025);
FORCEPROP 1 LAST PATH I36
J 0
(-7975 5200);
DISPLAY 0.978723 (-7975 5200);
PAINT WHITE (-7975 5200);
DISPLAY INVISIBLE (-7975 5200);
FORCEPROP 1 LAST PART_NUMBER CS24701JE04
J 0
(-7985 4900);
DISPLAY 0.978723 (-7985 4900);
DISPLAY INVISIBLE (-7985 4900);
FORCEADD Q_RES..2
(-7725 5025);
FORCEPROP 1 LAST LOCATION R1035
J 0
(-7680 5150);
DISPLAY 0.787234 (-7680 5150);
FORCEPROP 0 LAST $SEC 1
J 0
(-7675 5200);
DISPLAY 0.680851 (-7675 5200);
PAINT MONO (-7675 5200);
DISPLAY INVISIBLE (-7675 5200);
FORCEPROP 0 LAST CDS_SEC 1
J 0
(-7675 5200);
DISPLAY 0.680851 (-7675 5200);
DISPLAY INVISIBLE (-7675 5200);
FORCEPROP 1 LASTPIN (-7725 5125) $PN 1
J 0
(-7720 5087);
DISPLAY 0.787234 (-7720 5087);
PAINT MONO (-7720 5087);
FORCEPROP 1 LASTPIN (-7725 4925) $PN 2
J 0
(-7720 4935);
DISPLAY 0.787234 (-7720 4935);
PAINT MONO (-7720 4935);
FORCEPROP 1 LAST PACK_TYPE 0201LF
J 0
(-7685 4850);
DISPLAY 0.787234 (-7685 4850);
FORCEPROP 1 LAST VALUE 4.7K
J 0
(-7680 5100);
DISPLAY 0.787234 (-7680 5100);
FORCEPROP 1 LAST TOLERANCE 5%
J 0
(-7680 5050);
DISPLAY 0.787234 (-7680 5050);
FORCEPROP 1 LAST WATTAGE 1/20W
J 0
(-7685 5000);
DISPLAY 0.787234 (-7685 5000);
FORCEPROP 1 LAST MATERIAL CHIP
J 0
(-7685 4950);
DISPLAY 0.787234 (-7685 4950);
FORCEPROP 2 LAST CDS_LIB pure_quanta
J 0
(-7725 5025);
DISPLAY INVISIBLE (-7725 5025);
FORCEPROP 1 LAST PATH I37
J 0
(-7675 5200);
DISPLAY 0.978723 (-7675 5200);
PAINT WHITE (-7675 5200);
DISPLAY INVISIBLE (-7675 5200);
FORCEPROP 1 LAST PART_NUMBER CS24701JE04
J 0
(-7685 4900);
DISPLAY 0.787234 (-7685 4900);
DISPLAY INVISIBLE (-7685 4900);
FORCEADD UNIVERSAL_GND..1
(-7425 4550);
FORCEPROP 3 LASTPIN (-7425 4600) SIG_NAME GND\g
J 0
(-7415 4610);
DISPLAY 0.659574 (-7415 4610);
PAINT MONO (-7415 4610);
DISPLAY INVISIBLE (-7415 4610);
FORCEPROP 2 LAST CDS_LIB pure_quanta_power
J 0
(-7425 4550);
DISPLAY INVISIBLE (-7425 4550);
FORCEPROP 1 LAST HDL_POWER GND
J 1
(-7400 4475);
DISPLAY 0.872340 (-7400 4475);
PAINT GREEN (-7400 4475);
DISPLAY INVISIBLE (-7400 4475);
FORCEPROP 1 LAST PATH I38
J 0
(-7350 4550);
DISPLAY 0.872340 (-7350 4550);
PAINT AQUA (-7350 4550);
DISPLAY INVISIBLE (-7350 4550);
FORCEADD Q_RES..2
(-7425 5000);
FORCEPROP 1 LAST LOCATION R1037
J 0
(-7380 5125);
DISPLAY 0.787234 (-7380 5125);
FORCEPROP 0 LAST $SEC 1
J 0
(-7375 5175);
DISPLAY 0.680851 (-7375 5175);
PAINT MONO (-7375 5175);
DISPLAY INVISIBLE (-7375 5175);
FORCEPROP 0 LAST CDS_SEC 1
J 0
(-7375 5175);
DISPLAY 0.680851 (-7375 5175);
DISPLAY INVISIBLE (-7375 5175);
FORCEPROP 1 LASTPIN (-7425 5100) $PN 1
J 0
(-7420 5062);
DISPLAY 0.787234 (-7420 5062);
PAINT MONO (-7420 5062);
FORCEPROP 1 LASTPIN (-7425 4900) $PN 2
J 0
(-7420 4910);
DISPLAY 0.787234 (-7420 4910);
PAINT MONO (-7420 4910);
FORCEPROP 1 LAST TOLERANCE 5%
J 0
(-7380 5025);
DISPLAY 0.787234 (-7380 5025);
FORCEPROP 1 LAST MATERIAL CHIP
J 0
(-7385 4925);
DISPLAY 0.787234 (-7385 4925);
FORCEPROP 1 LAST WATTAGE 1/20W
J 0
(-7385 4975);
DISPLAY 0.787234 (-7385 4975);
FORCEPROP 1 LAST PACK_TYPE 0201LF
J 0
(-7385 4825);
DISPLAY 0.787234 (-7385 4825);
FORCEPROP 1 LAST VALUE 4.7K
J 0
(-7380 5075);
DISPLAY 0.787234 (-7380 5075);
FORCEPROP 2 LAST CDS_LIB pure_quanta
J 0
(-7425 5000);
DISPLAY INVISIBLE (-7425 5000);
FORCEPROP 1 LAST PATH I39
J 0
(-7375 5175);
DISPLAY 0.978723 (-7375 5175);
PAINT WHITE (-7375 5175);
DISPLAY INVISIBLE (-7375 5175);
FORCEPROP 1 LAST PART_NUMBER CS24701JE04
J 0
(-7385 4875);
DISPLAY 0.638298 (-7385 4875);
DISPLAY INVISIBLE (-7385 4875);
FORCEADD Q_RES..2
(-8025 5950);
FORCEPROP 1 LAST LOCATION R1032
J 0
(-7980 6075);
DISPLAY 0.787234 (-7980 6075);
FORCEPROP 0 LAST $SEC 1
J 0
(-7975 6125);
DISPLAY 0.680851 (-7975 6125);
PAINT MONO (-7975 6125);
DISPLAY INVISIBLE (-7975 6125);
FORCEPROP 0 LAST CDS_SEC 1
J 0
(-7975 6125);
DISPLAY 0.680851 (-7975 6125);
DISPLAY INVISIBLE (-7975 6125);
FORCEPROP 1 LASTPIN (-8025 6050) $PN 1
J 0
(-8020 6012);
DISPLAY 0.787234 (-8020 6012);
PAINT MONO (-8020 6012);
FORCEPROP 1 LASTPIN (-8025 5850) $PN 2
J 0
(-8020 5860);
DISPLAY 0.787234 (-8020 5860);
PAINT MONO (-8020 5860);
FORCEPROP 1 LAST PACK_TYPE 0201LF
J 0
(-7975 5800);
DISPLAY 0.787234 (-7975 5800);
FORCEPROP 1 LAST MATERIAL EMPTY
J 0
(-7985 5875);
DISPLAY 0.787234 (-7985 5875);
FORCEPROP 1 LAST TOLERANCE 5%
J 0
(-7980 5975);
DISPLAY 0.787234 (-7980 5975);
FORCEPROP 1 LAST VALUE 4.7K
J 0
(-7980 6025);
DISPLAY 0.787234 (-7980 6025);
FORCEPROP 1 LAST WATTAGE 1/20W
J 0
(-7985 5925);
DISPLAY 0.787234 (-7985 5925);
FORCEPROP 2 LAST CDS_LIB pure_quanta
J 0
(-8025 5950);
DISPLAY INVISIBLE (-8025 5950);
FORCEPROP 1 LAST PATH I40
J 0
(-7975 6125);
DISPLAY 0.978723 (-7975 6125);
PAINT WHITE (-7975 6125);
DISPLAY INVISIBLE (-7975 6125);
FORCEPROP 1 LAST PART_NUMBER CS24701JE04
J 0
(-7985 5825);
DISPLAY 0.978723 (-7985 5825);
DISPLAY INVISIBLE (-7985 5825);
FORCEADD Q_RES..2
(-7725 5975);
FORCEPROP 1 LAST LOCATION R1034
J 0
(-7680 6100);
DISPLAY 0.787234 (-7680 6100);
FORCEPROP 0 LAST $SEC 1
J 0
(-7675 6150);
DISPLAY 0.680851 (-7675 6150);
PAINT MONO (-7675 6150);
DISPLAY INVISIBLE (-7675 6150);
FORCEPROP 0 LAST CDS_SEC 1
J 0
(-7675 6150);
DISPLAY 0.680851 (-7675 6150);
DISPLAY INVISIBLE (-7675 6150);
FORCEPROP 1 LASTPIN (-7725 6075) $PN 1
J 0
(-7720 6037);
DISPLAY 0.787234 (-7720 6037);
PAINT MONO (-7720 6037);
FORCEPROP 1 LASTPIN (-7725 5875) $PN 2
J 0
(-7720 5885);
DISPLAY 0.787234 (-7720 5885);
PAINT MONO (-7720 5885);
FORCEPROP 1 LAST WATTAGE 1/20W
J 0
(-7685 5950);
DISPLAY 0.787234 (-7685 5950);
FORCEPROP 1 LAST MATERIAL EMPTY
J 0
(-7685 5900);
DISPLAY 0.787234 (-7685 5900);
FORCEPROP 1 LAST VALUE 4.7K
J 0
(-7680 6050);
DISPLAY 0.787234 (-7680 6050);
FORCEPROP 1 LAST TOLERANCE 5%
J 0
(-7680 6000);
DISPLAY 0.787234 (-7680 6000);
FORCEPROP 1 LAST PACK_TYPE 0201LF
J 0
(-7685 5800);
DISPLAY 0.787234 (-7685 5800);
FORCEPROP 2 LAST CDS_LIB pure_quanta
J 0
(-7725 5975);
DISPLAY INVISIBLE (-7725 5975);
FORCEPROP 1 LAST PATH I41
J 0
(-7675 6150);
DISPLAY 0.978723 (-7675 6150);
PAINT WHITE (-7675 6150);
DISPLAY INVISIBLE (-7675 6150);
FORCEPROP 1 LAST PART_NUMBER CS24701JE04
J 0
(-7685 5850);
DISPLAY 0.787234 (-7685 5850);
DISPLAY INVISIBLE (-7685 5850);
FORCEADD Q_RES..2
(-7425 6000);
FORCEPROP 1 LAST LOCATION R1024
J 0
(-7380 6125);
DISPLAY 0.787234 (-7380 6125);
FORCEPROP 0 LAST $SEC 1
J 0
(-7375 6175);
DISPLAY 0.680851 (-7375 6175);
PAINT MONO (-7375 6175);
DISPLAY INVISIBLE (-7375 6175);
FORCEPROP 0 LAST CDS_SEC 1
J 0
(-7375 6175);
DISPLAY 0.680851 (-7375 6175);
DISPLAY INVISIBLE (-7375 6175);
FORCEPROP 1 LASTPIN (-7425 6100) $PN 1
J 0
(-7420 6062);
DISPLAY 0.787234 (-7420 6062);
PAINT MONO (-7420 6062);
FORCEPROP 1 LASTPIN (-7425 5900) $PN 2
J 0
(-7420 5910);
DISPLAY 0.787234 (-7420 5910);
PAINT MONO (-7420 5910);
FORCEPROP 1 LAST MATERIAL EMPTY
J 0
(-7385 5925);
DISPLAY 0.787234 (-7385 5925);
FORCEPROP 1 LAST WATTAGE 1/20W
J 0
(-7385 5975);
DISPLAY 0.787234 (-7385 5975);
FORCEPROP 1 LAST VALUE 4.7K
J 0
(-7380 6075);
DISPLAY 0.787234 (-7380 6075);
FORCEPROP 1 LAST TOLERANCE 5%
J 0
(-7380 6025);
DISPLAY 0.787234 (-7380 6025);
FORCEPROP 1 LAST PACK_TYPE 0201LF
J 0
(-7375 5825);
DISPLAY 0.787234 (-7375 5825);
FORCEPROP 2 LAST CDS_LIB pure_quanta
J 0
(-7425 6000);
DISPLAY INVISIBLE (-7425 6000);
FORCEPROP 1 LAST PATH I42
J 0
(-7375 6175);
DISPLAY 0.978723 (-7375 6175);
PAINT WHITE (-7375 6175);
DISPLAY INVISIBLE (-7375 6175);
FORCEPROP 1 LAST PART_NUMBER CS24701JE04
J 0
(-7375 5875);
DISPLAY 0.638298 (-7375 5875);
DISPLAY INVISIBLE (-7375 5875);
FORCEADD OFFPAGE..5
R 2
(-6375 5625);
FORCEPROP 2 LAST $XR0 288 
J 0
(-6186 5625);
DISPLAY 0.638298 (-6186 5625);
PAINT MONO (-6186 5625);
FORCEPROP 2 LAST CDS_LIB standard
J 0
(-6375 5625);
DISPLAY INVISIBLE (-6375 5625);
FORCEPROP 1 LAST OFFPAGE TRUE
J 2
(-6700 5500);
DISPLAY 0.872340 (-6700 5500);
PAINT GREEN (-6700 5500);
DISPLAY INVISIBLE (-6700 5500);
FORCEPROP 1 LAST COMMENT_BODY TRUE
J 2
(-6475 5550);
DISPLAY 0.872340 (-6475 5550);
PAINT GREEN (-6475 5550);
DISPLAY INVISIBLE (-6475 5550);
FORCEPROP 2 LAST PATH I43
J 0
(-6175 5675);
DISPLAY 0.680851 (-6175 5675);
DISPLAY INVISIBLE (-6175 5675);
FORCEADD OFFPAGE..5
R 2
(-6375 5575);
FORCEPROP 2 LAST $XR0 288 
J 0
(-6186 5575);
DISPLAY 0.638298 (-6186 5575);
PAINT MONO (-6186 5575);
FORCEPROP 2 LAST CDS_LIB standard
J 0
(-6375 5575);
DISPLAY INVISIBLE (-6375 5575);
FORCEPROP 1 LAST OFFPAGE TRUE
J 2
(-6700 5450);
DISPLAY 0.872340 (-6700 5450);
PAINT GREEN (-6700 5450);
DISPLAY INVISIBLE (-6700 5450);
FORCEPROP 1 LAST COMMENT_BODY TRUE
J 2
(-6475 5500);
DISPLAY 0.872340 (-6475 5500);
PAINT GREEN (-6475 5500);
DISPLAY INVISIBLE (-6475 5500);
FORCEPROP 2 LAST PATH I44
J 0
(-6175 5625);
DISPLAY 0.680851 (-6175 5625);
DISPLAY INVISIBLE (-6175 5625);
FORCEADD OFFPAGE..5
R 2
(-6375 5525);
FORCEPROP 2 LAST $XR0 288 
J 0
(-6186 5525);
DISPLAY 0.638298 (-6186 5525);
PAINT MONO (-6186 5525);
FORCEPROP 2 LAST CDS_LIB standard
J 0
(-6375 5525);
DISPLAY INVISIBLE (-6375 5525);
FORCEPROP 1 LAST OFFPAGE TRUE
J 2
(-6700 5400);
DISPLAY 0.872340 (-6700 5400);
PAINT GREEN (-6700 5400);
DISPLAY INVISIBLE (-6700 5400);
FORCEPROP 1 LAST COMMENT_BODY TRUE
J 2
(-6475 5450);
DISPLAY 0.872340 (-6475 5450);
PAINT GREEN (-6475 5450);
DISPLAY INVISIBLE (-6475 5450);
FORCEPROP 2 LAST PATH I45
J 0
(-6175 5575);
DISPLAY 0.680851 (-6175 5575);
DISPLAY INVISIBLE (-6175 5575);
FORCEADD OFFPAGE..5
R 2
(-6375 5475);
FORCEPROP 2 LAST $XR0 288 
J 0
(-6186 5475);
DISPLAY 0.638298 (-6186 5475);
PAINT MONO (-6186 5475);
FORCEPROP 2 LAST CDS_LIB standard
J 0
(-6375 5475);
DISPLAY INVISIBLE (-6375 5475);
FORCEPROP 1 LAST OFFPAGE TRUE
J 2
(-6700 5350);
DISPLAY 0.872340 (-6700 5350);
PAINT GREEN (-6700 5350);
DISPLAY INVISIBLE (-6700 5350);
FORCEPROP 1 LAST COMMENT_BODY TRUE
J 2
(-6475 5400);
DISPLAY 0.872340 (-6475 5400);
PAINT GREEN (-6475 5400);
DISPLAY INVISIBLE (-6475 5400);
FORCEPROP 2 LAST PATH I46
J 0
(-6175 5525);
DISPLAY 0.680851 (-6175 5525);
DISPLAY INVISIBLE (-6175 5525);
FORCEADD OFFPAGE..5
R 2
(-6375 5400);
FORCEPROP 2 LAST $XR0 288 
J 0
(-6186 5400);
DISPLAY 0.638298 (-6186 5400);
PAINT MONO (-6186 5400);
FORCEPROP 2 LAST CDS_LIB standard
J 0
(-6375 5400);
DISPLAY INVISIBLE (-6375 5400);
FORCEPROP 1 LAST OFFPAGE TRUE
J 2
(-6700 5275);
DISPLAY 0.872340 (-6700 5275);
PAINT GREEN (-6700 5275);
DISPLAY INVISIBLE (-6700 5275);
FORCEPROP 1 LAST COMMENT_BODY TRUE
J 2
(-6475 5325);
DISPLAY 0.872340 (-6475 5325);
PAINT GREEN (-6475 5325);
DISPLAY INVISIBLE (-6475 5325);
FORCEPROP 2 LAST PATH I47
J 0
(-6175 5450);
DISPLAY 0.680851 (-6175 5450);
DISPLAY INVISIBLE (-6175 5450);
FORCEADD OFFPAGE..5
R 2
(-6375 5700);
FORCEPROP 2 LAST $XR0 288 
J 0
(-6186 5700);
DISPLAY 0.638298 (-6186 5700);
PAINT MONO (-6186 5700);
FORCEPROP 2 LAST CDS_LIB standard
J 0
(-6375 5700);
DISPLAY INVISIBLE (-6375 5700);
FORCEPROP 1 LAST OFFPAGE TRUE
J 2
(-6700 5575);
DISPLAY 0.872340 (-6700 5575);
PAINT GREEN (-6700 5575);
DISPLAY INVISIBLE (-6700 5575);
FORCEPROP 1 LAST COMMENT_BODY TRUE
J 2
(-6475 5625);
DISPLAY 0.872340 (-6475 5625);
PAINT GREEN (-6475 5625);
DISPLAY INVISIBLE (-6475 5625);
FORCEPROP 2 LAST PATH I48
J 0
(-6175 5750);
DISPLAY 0.680851 (-6175 5750);
DISPLAY INVISIBLE (-6175 5750);
FORCEADD UNIVERSAL_GND..1
(-5025 5200);
FORCEPROP 3 LASTPIN (-5025 5250) SIG_NAME GND\g
J 0
(-5015 5260);
DISPLAY 0.659574 (-5015 5260);
PAINT MONO (-5015 5260);
DISPLAY INVISIBLE (-5015 5260);
FORCEPROP 2 LAST CDS_LIB pure_quanta_power
J 0
(-5025 5200);
DISPLAY INVISIBLE (-5025 5200);
FORCEPROP 1 LAST HDL_POWER GND
J 1
(-5000 5125);
DISPLAY 0.872340 (-5000 5125);
PAINT GREEN (-5000 5125);
DISPLAY INVISIBLE (-5000 5125);
FORCEPROP 1 LAST PATH I49
J 0
(-4950 5200);
DISPLAY 0.872340 (-4950 5200);
PAINT AQUA (-4950 5200);
DISPLAY INVISIBLE (-4950 5200);
FORCEADD Q_RES..2
(-8975 4125);
FORCEPROP 1 LAST LOCATION R1021
J 0
(-8930 4250);
DISPLAY 0.787234 (-8930 4250);
FORCEPROP 0 LAST $SEC 1
J 0
(-8925 4300);
DISPLAY 0.680851 (-8925 4300);
PAINT MONO (-8925 4300);
DISPLAY INVISIBLE (-8925 4300);
FORCEPROP 0 LAST CDS_SEC 1
J 0
(-8925 4300);
DISPLAY 0.680851 (-8925 4300);
DISPLAY INVISIBLE (-8925 4300);
FORCEPROP 1 LASTPIN (-8975 4225) $PN 1
J 0
(-8970 4187);
DISPLAY 0.787234 (-8970 4187);
PAINT MONO (-8970 4187);
FORCEPROP 1 LASTPIN (-8975 4025) $PN 2
J 0
(-8970 4035);
DISPLAY 0.787234 (-8970 4035);
PAINT MONO (-8970 4035);
FORCEPROP 1 LAST VALUE 4.7K
J 0
(-8930 4200);
DISPLAY 0.787234 (-8930 4200);
FORCEPROP 1 LAST WATTAGE 1/20W
J 0
(-8935 4100);
DISPLAY 0.787234 (-8935 4100);
FORCEPROP 1 LAST PACK_TYPE 0201LF
J 0
(-8925 3975);
DISPLAY 0.787234 (-8925 3975);
FORCEPROP 1 LAST TOLERANCE 5%
J 0
(-8930 4150);
DISPLAY 0.787234 (-8930 4150);
FORCEPROP 1 LAST MATERIAL EMPTY
J 0
(-8935 4050);
DISPLAY 0.787234 (-8935 4050);
FORCEPROP 2 LAST CDS_LIB pure_quanta
J 0
(-8975 4125);
DISPLAY INVISIBLE (-8975 4125);
FORCEPROP 1 LAST PATH I5
J 0
(-8925 4300);
DISPLAY 0.978723 (-8925 4300);
PAINT WHITE (-8925 4300);
DISPLAY INVISIBLE (-8925 4300);
FORCEPROP 1 LAST PART_NUMBER CS24701JE04
J 0
(-8935 4000);
DISPLAY 0.978723 (-8935 4000);
DISPLAY INVISIBLE (-8935 4000);
FORCEADD Q_RES..2
(-5025 5550);
FORCEPROP 1 LAST LOCATION R1006
J 0
(-4980 5675);
DISPLAY 0.787234 (-4980 5675);
FORCEPROP 0 LAST $SEC 1
J 0
(-4975 5725);
DISPLAY 0.680851 (-4975 5725);
PAINT MONO (-4975 5725);
DISPLAY INVISIBLE (-4975 5725);
FORCEPROP 0 LAST CDS_SEC 1
J 0
(-4975 5725);
DISPLAY 0.680851 (-4975 5725);
DISPLAY INVISIBLE (-4975 5725);
FORCEPROP 1 LASTPIN (-5025 5650) $PN 1
J 0
(-5020 5612);
DISPLAY 0.787234 (-5020 5612);
PAINT MONO (-5020 5612);
FORCEPROP 1 LASTPIN (-5025 5450) $PN 2
J 0
(-5020 5460);
DISPLAY 0.787234 (-5020 5460);
PAINT MONO (-5020 5460);
FORCEPROP 1 LAST MATERIAL EMPTY
J 0
(-4985 5475);
DISPLAY 0.787234 (-4985 5475);
FORCEPROP 1 LAST WATTAGE 1/20W
J 0
(-4985 5525);
DISPLAY 0.787234 (-4985 5525);
FORCEPROP 1 LAST TOLERANCE 5%
J 0
(-4980 5575);
DISPLAY 0.787234 (-4980 5575);
FORCEPROP 1 LAST VALUE 4.7K
J 0
(-4980 5625);
DISPLAY 0.787234 (-4980 5625);
FORCEPROP 1 LAST PACK_TYPE 0201LF
J 0
(-4985 5375);
DISPLAY 0.787234 (-4985 5375);
FORCEPROP 2 LAST CDS_LIB pure_quanta
J 0
(-5025 5550);
DISPLAY INVISIBLE (-5025 5550);
FORCEPROP 1 LAST PATH I50
J 0
(-4975 5725);
DISPLAY 0.978723 (-4975 5725);
PAINT WHITE (-4975 5725);
DISPLAY INVISIBLE (-4975 5725);
FORCEPROP 1 LAST PART_NUMBER CS24701JE04
J 0
(-4985 5425);
DISPLAY 0.787234 (-4985 5425);
DISPLAY INVISIBLE (-4985 5425);
FORCEADD Q_RES..2
(-5025 6075);
FORCEPROP 1 LAST LOCATION R1039
J 0
(-4980 6200);
DISPLAY 0.787234 (-4980 6200);
FORCEPROP 0 LAST $SEC 1
J 0
(-4975 6250);
DISPLAY 0.680851 (-4975 6250);
PAINT MONO (-4975 6250);
DISPLAY INVISIBLE (-4975 6250);
FORCEPROP 0 LAST CDS_SEC 1
J 0
(-4975 6250);
DISPLAY 0.680851 (-4975 6250);
DISPLAY INVISIBLE (-4975 6250);
FORCEPROP 1 LASTPIN (-5025 6175) $PN 1
J 0
(-5020 6137);
DISPLAY 0.787234 (-5020 6137);
PAINT MONO (-5020 6137);
FORCEPROP 1 LASTPIN (-5025 5975) $PN 2
J 0
(-5020 5985);
DISPLAY 0.787234 (-5020 5985);
PAINT MONO (-5020 5985);
FORCEPROP 1 LAST PACK_TYPE 0201LF
J 0
(-4985 5900);
DISPLAY 0.787234 (-4985 5900);
FORCEPROP 1 LAST MATERIAL CHIP
J 0
(-4985 6000);
DISPLAY 0.787234 (-4985 6000);
FORCEPROP 1 LAST TOLERANCE 5%
J 0
(-4980 6100);
DISPLAY 0.787234 (-4980 6100);
FORCEPROP 1 LAST VALUE 4.7K
J 0
(-4980 6150);
DISPLAY 0.787234 (-4980 6150);
FORCEPROP 1 LAST WATTAGE 1/20W
J 0
(-4985 6050);
DISPLAY 0.787234 (-4985 6050);
FORCEPROP 2 LAST CDS_LIB pure_quanta
J 0
(-5025 6075);
DISPLAY INVISIBLE (-5025 6075);
FORCEPROP 1 LAST PATH I51
J 0
(-4975 6250);
DISPLAY 0.978723 (-4975 6250);
PAINT WHITE (-4975 6250);
DISPLAY INVISIBLE (-4975 6250);
FORCEPROP 1 LAST PART_NUMBER CS24701JE04
J 0
(-4985 5950);
DISPLAY 0.787234 (-4985 5950);
DISPLAY INVISIBLE (-4985 5950);
FORCEADD OFFPAGE..5
R 2
(-4150 5800);
FORCEPROP 2 LAST $XR0 288 
J 0
(-3961 5800);
DISPLAY 0.638298 (-3961 5800);
PAINT MONO (-3961 5800);
FORCEPROP 2 LAST CDS_LIB standard
J 0
(-4150 5800);
DISPLAY INVISIBLE (-4150 5800);
FORCEPROP 1 LAST OFFPAGE TRUE
J 2
(-4475 5675);
DISPLAY 0.872340 (-4475 5675);
PAINT GREEN (-4475 5675);
DISPLAY INVISIBLE (-4475 5675);
FORCEPROP 1 LAST COMMENT_BODY TRUE
J 2
(-4250 5725);
DISPLAY 0.872340 (-4250 5725);
PAINT GREEN (-4250 5725);
DISPLAY INVISIBLE (-4250 5725);
FORCEPROP 2 LAST PATH I52
J 0
(-3950 5850);
DISPLAY 0.680851 (-3950 5850);
DISPLAY INVISIBLE (-3950 5850);
FORCEADD P1V0..1
(-5025 6400);
FORCEPROP 3 LASTPIN (-5025 6350) SIG_NAME P1V8_CPU0_RT_1D\g
J 0
(-5015 6360);
DISPLAY 0.659574 (-5015 6360);
PAINT MONO (-5015 6360);
DISPLAY INVISIBLE (-5015 6360);
FORCEPROP 1 LAST HDL_POWER P1V8_CPU0_RT_1D
J 1
(-5025 6450);
DISPLAY 0.489362 (-5025 6450);
FORCEPROP 2 LAST CDS_LIB pure_quanta_power
J 0
(-5025 6400);
DISPLAY INVISIBLE (-5025 6400);
FORCEPROP 1 LAST PATH I53
J 0
(-4975 6425);
DISPLAY 0.872340 (-4975 6425);
PAINT AQUA (-4975 6425);
DISPLAY INVISIBLE (-4975 6425);
FORCEADD UNIVERSAL_GND..1
R 1
(-3325 1700);
FORCEPROP 3 LASTPIN (-3375 1700) SIG_NAME GND\g
J 0
(-3365 1710);
DISPLAY 0.659574 (-3365 1710);
PAINT MONO (-3365 1710);
DISPLAY INVISIBLE (-3365 1710);
FORCEPROP 2 LAST CDS_LIB pure_quanta_power
J 0
(-3325 1700);
DISPLAY INVISIBLE (-3325 1700);
FORCEPROP 1 LAST HDL_POWER GND
R 1
J 1
(-3250 1725);
DISPLAY 0.872340 (-3250 1725);
PAINT GREEN (-3250 1725);
DISPLAY INVISIBLE (-3250 1725);
FORCEPROP 1 LAST PATH I54
R 1
J 0
(-3325 1775);
DISPLAY 0.872340 (-3325 1775);
PAINT AQUA (-3325 1775);
DISPLAY INVISIBLE (-3325 1775);
FORCEADD Q_RES..1
(-2575 2100);
FORCEPROP 1 LAST LOCATION R1012
J 0
(-2850 2100);
DISPLAY 0.978723 (-2850 2100);
FORCEPROP 0 LAST $SEC 1
J 0
(-2275 2150);
DISPLAY 0.680851 (-2275 2150);
PAINT MONO (-2275 2150);
DISPLAY INVISIBLE (-2275 2150);
FORCEPROP 0 LAST CDS_SEC 1
J 0
(-2275 2150);
DISPLAY 0.680851 (-2275 2150);
DISPLAY INVISIBLE (-2275 2150);
FORCEPROP 1 LASTPIN (-2675 2100) $PN 1
J 0
(-2663 2112);
DISPLAY 0.787234 (-2663 2112);
PAINT MONO (-2663 2112);
FORCEPROP 1 LASTPIN (-2475 2100) $PN 2
J 0
(-2513 2112);
DISPLAY 0.787234 (-2513 2112);
PAINT MONO (-2513 2112);
FORCEPROP 1 LAST PACK_TYPE 0201LF
J 0
(-2275 2100);
DISPLAY 0.787234 (-2275 2100);
FORCEPROP 1 LAST VALUE 0
J 2
(-2375 2100);
DISPLAY 0.787234 (-2375 2100);
FORCEPROP 2 LAST CDS_LIB pure_quanta
J 0
(-2575 2100);
DISPLAY INVISIBLE (-2575 2100);
FORCEPROP 1 LAST MATERIAL CHIP
J 0
(-2750 2175);
DISPLAY 0.787234 (-2750 2175);
DISPLAY INVISIBLE (-2750 2175);
FORCEPROP 1 LAST TOLERANCE 5%
J 0
(-2750 2225);
DISPLAY 0.787234 (-2750 2225);
DISPLAY INVISIBLE (-2750 2225);
FORCEPROP 1 LAST WATTAGE 1/20W
J 2
(-2775 2175);
DISPLAY 0.787234 (-2775 2175);
DISPLAY INVISIBLE (-2775 2175);
FORCEPROP 1 LAST PATH I55
J 0
(-2625 2250);
DISPLAY 0.978723 (-2625 2250);
PAINT WHITE (-2625 2250);
DISPLAY INVISIBLE (-2625 2250);
FORCEPROP 1 LAST PART_NUMBER CS00001JE10
J 0
(-2625 2225);
DISPLAY 0.808511 (-2625 2225);
DISPLAY INVISIBLE (-2625 2225);
FORCEADD Q_RES..1
(-2575 2200);
FORCEPROP 1 LAST LOCATION R1004
J 0
(-2850 2200);
DISPLAY 0.978723 (-2850 2200);
FORCEPROP 2 LAST SEC 1
J 0
(-2625 2400);
DISPLAY 0.680851 (-2625 2400);
PAINT MONO (-2625 2400);
DISPLAY INVISIBLE (-2625 2400);
FORCEPROP 1 LASTPIN (-2675 2200) $PN 1
J 0
(-2663 2212);
DISPLAY 0.787234 (-2663 2212);
PAINT MONO (-2663 2212);
FORCEPROP 1 LASTPIN (-2475 2200) $PN 2
J 0
(-2513 2212);
DISPLAY 0.787234 (-2513 2212);
PAINT MONO (-2513 2212);
FORCEPROP 1 LAST PACK_TYPE 0201LF
J 0
(-2275 2200);
DISPLAY 0.787234 (-2275 2200);
FORCEPROP 1 LAST VALUE 0
J 2
(-2375 2200);
DISPLAY 0.787234 (-2375 2200);
FORCEPROP 1 LAST WATTAGE 1/20W
J 2
(-2775 2275);
DISPLAY 0.787234 (-2775 2275);
DISPLAY INVISIBLE (-2775 2275);
FORCEPROP 1 LAST TOLERANCE 5%
J 0
(-2750 2325);
DISPLAY 0.787234 (-2750 2325);
DISPLAY INVISIBLE (-2750 2325);
FORCEPROP 1 LAST MATERIAL CHIP
J 0
(-2750 2275);
DISPLAY 0.787234 (-2750 2275);
DISPLAY INVISIBLE (-2750 2275);
FORCEPROP 2 LAST SEC_TYPE 0201LF
J 0
(-2625 2400);
DISPLAY 0.680851 (-2625 2400);
DISPLAY INVISIBLE (-2625 2400);
FORCEPROP 2 LAST CDS_LIB pure_quanta
J 0
(-2575 2200);
DISPLAY INVISIBLE (-2575 2200);
FORCEPROP 1 LAST PATH I56
J 0
(-2625 2350);
DISPLAY 0.978723 (-2625 2350);
PAINT WHITE (-2625 2350);
DISPLAY INVISIBLE (-2625 2350);
FORCEPROP 1 LAST PART_NUMBER CS00001JE10
J 0
(-2625 2325);
DISPLAY 0.808511 (-2625 2325);
DISPLAY INVISIBLE (-2625 2325);
FORCEADD OFFPAGE..1
R 2
(-2375 2600);
FORCEPROP 2 LAST $XR0 288 
J 0
(-2189 2600);
DISPLAY 0.638298 (-2189 2600);
PAINT MONO (-2189 2600);
FORCEPROP 2 LAST CDS_LIB standard
J 0
(-2375 2600);
DISPLAY INVISIBLE (-2375 2600);
FORCEPROP 1 LAST OFFPAGE TRUE
J 2
(-2700 2475);
DISPLAY 0.872340 (-2700 2475);
DISPLAY INVISIBLE (-2700 2475);
FORCEPROP 1 LAST COMMENT_BODY TRUE
J 2
(-2500 2500);
DISPLAY 0.872340 (-2500 2500);
PAINT GREEN (-2500 2500);
DISPLAY INVISIBLE (-2500 2500);
FORCEPROP 2 LAST PATH I58
J 0
(-2175 2650);
DISPLAY 0.680851 (-2175 2650);
DISPLAY INVISIBLE (-2175 2650);
FORCEADD OFFPAGE..1
R 2
(-2475 3100);
FORCEPROP 2 LAST $XR0 288 
J 0
(-2289 3100);
DISPLAY 0.638298 (-2289 3100);
PAINT MONO (-2289 3100);
FORCEPROP 2 LAST CDS_LIB standard
J 0
(-2475 3100);
DISPLAY INVISIBLE (-2475 3100);
FORCEPROP 1 LAST OFFPAGE TRUE
J 2
(-2800 2975);
DISPLAY 0.872340 (-2800 2975);
DISPLAY INVISIBLE (-2800 2975);
FORCEPROP 1 LAST COMMENT_BODY TRUE
J 2
(-2600 3000);
DISPLAY 0.872340 (-2600 3000);
PAINT GREEN (-2600 3000);
DISPLAY INVISIBLE (-2600 3000);
FORCEPROP 2 LAST PATH I59
J 0
(-2275 3150);
DISPLAY 0.680851 (-2275 3150);
DISPLAY INVISIBLE (-2275 3150);
FORCEADD P1V0..1
(-8975 4450);
FORCEPROP 3 LASTPIN (-8975 4400) SIG_NAME P1V8_CPU0_RT_1D\g
J 0
(-8965 4410);
DISPLAY 0.659574 (-8965 4410);
PAINT MONO (-8965 4410);
DISPLAY INVISIBLE (-8965 4410);
FORCEPROP 1 LAST HDL_POWER P1V8_CPU0_RT_1D
J 1
(-8975 4500);
DISPLAY 0.489362 (-8975 4500);
FORCEPROP 2 LAST CDS_LIB pure_quanta_power
J 0
(-8975 4450);
DISPLAY INVISIBLE (-8975 4450);
FORCEPROP 1 LAST PATH I6
J 0
(-8925 4475);
DISPLAY 0.872340 (-8925 4475);
PAINT AQUA (-8925 4475);
DISPLAY INVISIBLE (-8925 4475);
FORCEADD OFFPAGE..1
R 2
(-1050 2100);
FORCEPROP 2 LAST $XR1 288 
J 0
(-774 2100);
DISPLAY 0.638298 (-774 2100);
PAINT MONO (-774 2100);
FORCEPROP 2 LAST $XR0 81 
J 0
(-864 2100);
DISPLAY 0.638298 (-864 2100);
PAINT MONO (-864 2100);
FORCEPROP 2 LAST CDS_LIB standard
J 0
(-1050 2100);
DISPLAY INVISIBLE (-1050 2100);
FORCEPROP 1 LAST OFFPAGE TRUE
J 2
(-1375 1975);
DISPLAY 0.872340 (-1375 1975);
DISPLAY INVISIBLE (-1375 1975);
FORCEPROP 1 LAST COMMENT_BODY TRUE
J 2
(-1175 2000);
DISPLAY 0.872340 (-1175 2000);
PAINT GREEN (-1175 2000);
DISPLAY INVISIBLE (-1175 2000);
FORCEPROP 2 LAST PATH I61
J 0
(-750 2150);
DISPLAY 0.680851 (-750 2150);
DISPLAY INVISIBLE (-750 2150);
FORCEADD OFFPAGE..1
R 2
(-1050 2200);
FORCEPROP 2 LAST $XR1 288 
J 0
(-774 2200);
DISPLAY 0.638298 (-774 2200);
PAINT MONO (-774 2200);
FORCEPROP 2 LAST $XR0 81 
J 0
(-864 2200);
DISPLAY 0.638298 (-864 2200);
PAINT MONO (-864 2200);
FORCEPROP 2 LAST CDS_LIB standard
J 0
(-1050 2200);
DISPLAY INVISIBLE (-1050 2200);
FORCEPROP 1 LAST OFFPAGE TRUE
J 2
(-1375 2075);
DISPLAY 0.872340 (-1375 2075);
DISPLAY INVISIBLE (-1375 2075);
FORCEPROP 1 LAST COMMENT_BODY TRUE
J 2
(-1175 2100);
DISPLAY 0.872340 (-1175 2100);
PAINT GREEN (-1175 2100);
DISPLAY INVISIBLE (-1175 2100);
FORCEPROP 2 LAST PATH I62
J 0
(-750 2250);
DISPLAY 0.680851 (-750 2250);
DISPLAY INVISIBLE (-750 2250);
FORCEADD UNIVERSAL_GND..1
(-3475 4800);
FORCEPROP 3 LASTPIN (-3475 4850) SIG_NAME GND\g
J 0
(-3465 4860);
DISPLAY 0.659574 (-3465 4860);
PAINT MONO (-3465 4860);
DISPLAY INVISIBLE (-3465 4860);
FORCEPROP 2 LAST CDS_LIB pure_quanta_power
J 0
(-3475 4800);
DISPLAY INVISIBLE (-3475 4800);
FORCEPROP 1 LAST HDL_POWER GND
J 1
(-3450 4725);
DISPLAY 0.872340 (-3450 4725);
PAINT GREEN (-3450 4725);
DISPLAY INVISIBLE (-3450 4725);
FORCEPROP 1 LAST PATH I63
J 0
(-3400 4800);
DISPLAY 0.872340 (-3400 4800);
PAINT AQUA (-3400 4800);
DISPLAY INVISIBLE (-3400 4800);
FORCEADD Q_RES..2
(-3475 5225);
FORCEPROP 1 LAST LOCATION R1014
J 0
(-3430 5350);
DISPLAY 0.787234 (-3430 5350);
FORCEPROP 0 LAST $SEC 1
J 0
(-3425 5400);
DISPLAY 0.680851 (-3425 5400);
PAINT MONO (-3425 5400);
DISPLAY INVISIBLE (-3425 5400);
FORCEPROP 0 LAST CDS_SEC 1
J 0
(-3425 5400);
DISPLAY 0.680851 (-3425 5400);
DISPLAY INVISIBLE (-3425 5400);
FORCEPROP 1 LASTPIN (-3475 5325) $PN 1
J 0
(-3470 5287);
DISPLAY 0.787234 (-3470 5287);
PAINT MONO (-3470 5287);
FORCEPROP 1 LASTPIN (-3475 5125) $PN 2
J 0
(-3470 5135);
DISPLAY 0.787234 (-3470 5135);
PAINT MONO (-3470 5135);
FORCEPROP 1 LAST VALUE 1K
J 0
(-3430 5300);
DISPLAY 0.787234 (-3430 5300);
FORCEPROP 1 LAST WATTAGE 1/20W
J 0
(-3435 5200);
DISPLAY 0.787234 (-3435 5200);
FORCEPROP 1 LAST PACK_TYPE 0201LF
J 0
(-3435 5050);
DISPLAY 0.787234 (-3435 5050);
FORCEPROP 1 LAST MATERIAL EMPTY
J 0
(-3435 5150);
DISPLAY 0.787234 (-3435 5150);
FORCEPROP 1 LAST TOLERANCE 1%
J 0
(-3430 5250);
DISPLAY 0.787234 (-3430 5250);
FORCEPROP 2 LAST CDS_LIB pure_quanta
J 0
(-3475 5225);
DISPLAY INVISIBLE (-3475 5225);
FORCEPROP 1 LAST PATH I64
J 0
(-3425 5400);
DISPLAY 0.978723 (-3425 5400);
PAINT WHITE (-3425 5400);
DISPLAY INVISIBLE (-3425 5400);
FORCEPROP 1 LAST PART_NUMBER CS21001FE07
J 0
(-3435 5100);
DISPLAY 0.978723 (-3435 5100);
DISPLAY INVISIBLE (-3435 5100);
FORCEADD Q_RES..2
(-3175 5225);
FORCEPROP 1 LAST LOCATION R1016
J 0
(-3130 5350);
DISPLAY 0.787234 (-3130 5350);
FORCEPROP 0 LAST $SEC 1
J 0
(-3125 5400);
DISPLAY 0.680851 (-3125 5400);
PAINT MONO (-3125 5400);
DISPLAY INVISIBLE (-3125 5400);
FORCEPROP 0 LAST CDS_SEC 1
J 0
(-3125 5400);
DISPLAY 0.680851 (-3125 5400);
DISPLAY INVISIBLE (-3125 5400);
FORCEPROP 1 LASTPIN (-3175 5325) $PN 1
J 0
(-3170 5287);
DISPLAY 0.787234 (-3170 5287);
PAINT MONO (-3170 5287);
FORCEPROP 1 LASTPIN (-3175 5125) $PN 2
J 0
(-3170 5135);
DISPLAY 0.787234 (-3170 5135);
PAINT MONO (-3170 5135);
FORCEPROP 1 LAST MATERIAL CHIP
J 0
(-3135 5150);
DISPLAY 0.787234 (-3135 5150);
FORCEPROP 1 LAST VALUE 20K
J 0
(-3130 5300);
DISPLAY 0.787234 (-3130 5300);
FORCEPROP 1 LAST PACK_TYPE 0201LF
J 0
(-3135 5050);
DISPLAY 0.787234 (-3135 5050);
FORCEPROP 1 LAST TOLERANCE 1%
J 0
(-3130 5250);
DISPLAY 0.787234 (-3130 5250);
FORCEPROP 1 LAST WATTAGE 1/20W
J 0
(-3135 5200);
DISPLAY 0.787234 (-3135 5200);
FORCEPROP 2 LAST CDS_LIB pure_quanta
J 0
(-3175 5225);
DISPLAY INVISIBLE (-3175 5225);
FORCEPROP 1 LAST PATH I65
J 0
(-3125 5400);
DISPLAY 0.978723 (-3125 5400);
PAINT WHITE (-3125 5400);
DISPLAY INVISIBLE (-3125 5400);
FORCEPROP 1 LAST PART_NUMBER CS32001FE00
J 0
(-3135 5100);
DISPLAY 0.978723 (-3135 5100);
DISPLAY INVISIBLE (-3135 5100);
FORCEADD Q_RES..2
(-3475 6000);
FORCEPROP 1 LAST LOCATION R1013
J 0
(-3430 6125);
DISPLAY 0.787234 (-3430 6125);
FORCEPROP 0 LAST $SEC 1
J 0
(-3425 6175);
DISPLAY 0.680851 (-3425 6175);
PAINT MONO (-3425 6175);
DISPLAY INVISIBLE (-3425 6175);
FORCEPROP 0 LAST CDS_SEC 1
J 0
(-3425 6175);
DISPLAY 0.680851 (-3425 6175);
DISPLAY INVISIBLE (-3425 6175);
FORCEPROP 1 LASTPIN (-3475 6100) $PN 1
J 0
(-3470 6062);
DISPLAY 0.787234 (-3470 6062);
PAINT MONO (-3470 6062);
FORCEPROP 1 LASTPIN (-3475 5900) $PN 2
J 0
(-3470 5910);
DISPLAY 0.787234 (-3470 5910);
PAINT MONO (-3470 5910);
FORCEPROP 1 LAST TOLERANCE 1%
J 0
(-3430 6025);
DISPLAY 0.787234 (-3430 6025);
FORCEPROP 1 LAST VALUE 1K
J 0
(-3430 6075);
DISPLAY 0.787234 (-3430 6075);
FORCEPROP 1 LAST WATTAGE 1/20W
J 0
(-3435 5975);
DISPLAY 0.787234 (-3435 5975);
FORCEPROP 1 LAST MATERIAL CHIP
J 0
(-3435 5925);
DISPLAY 0.787234 (-3435 5925);
FORCEPROP 1 LAST PACK_TYPE 0201LF
J 0
(-3435 5825);
DISPLAY 0.787234 (-3435 5825);
FORCEPROP 2 LAST CDS_LIB pure_quanta
J 0
(-3475 6000);
DISPLAY INVISIBLE (-3475 6000);
FORCEPROP 1 LAST PATH I66
J 0
(-3425 6175);
DISPLAY 0.978723 (-3425 6175);
PAINT WHITE (-3425 6175);
DISPLAY INVISIBLE (-3425 6175);
FORCEPROP 1 LAST PART_NUMBER CS21001FE07
J 0
(-3435 5875);
DISPLAY 0.978723 (-3435 5875);
DISPLAY INVISIBLE (-3435 5875);
FORCEADD Q_RES..2
(-3175 6000);
FORCEPROP 1 LAST LOCATION R1015
J 0
(-3130 6125);
DISPLAY 0.978723 (-3130 6125);
FORCEPROP 0 LAST $SEC 1
J 0
(-3125 6175);
DISPLAY 0.680851 (-3125 6175);
PAINT MONO (-3125 6175);
DISPLAY INVISIBLE (-3125 6175);
FORCEPROP 0 LAST CDS_SEC 1
J 0
(-3125 6175);
DISPLAY 0.680851 (-3125 6175);
DISPLAY INVISIBLE (-3125 6175);
FORCEPROP 1 LASTPIN (-3175 6100) $PN 1
J 0
(-3170 6062);
DISPLAY 0.787234 (-3170 6062);
PAINT MONO (-3170 6062);
FORCEPROP 1 LASTPIN (-3175 5900) $PN 2
J 0
(-3170 5910);
DISPLAY 0.787234 (-3170 5910);
PAINT MONO (-3170 5910);
FORCEPROP 1 LAST WATTAGE 1/20W
J 0
(-3135 5975);
DISPLAY 0.787234 (-3135 5975);
FORCEPROP 1 LAST VALUE 1K
J 0
(-3130 6075);
DISPLAY 0.787234 (-3130 6075);
FORCEPROP 1 LAST MATERIAL EMPTY
J 0
(-3135 5925);
DISPLAY 0.787234 (-3135 5925);
FORCEPROP 1 LAST TOLERANCE 1%
J 0
(-3130 6025);
DISPLAY 0.787234 (-3130 6025);
FORCEPROP 1 LAST PACK_TYPE 0201LF
J 0
(-3135 5825);
DISPLAY 0.787234 (-3135 5825);
FORCEPROP 2 LAST CDS_LIB pure_quanta
J 0
(-3175 6000);
DISPLAY INVISIBLE (-3175 6000);
FORCEPROP 1 LAST PATH I67
J 0
(-3125 6175);
DISPLAY 0.978723 (-3125 6175);
PAINT WHITE (-3125 6175);
DISPLAY INVISIBLE (-3125 6175);
FORCEPROP 1 LAST PART_NUMBER CS21001FE07
J 0
(-3135 5875);
DISPLAY 0.978723 (-3135 5875);
DISPLAY INVISIBLE (-3135 5875);
FORCEADD Q_RES..2
(-2825 5225);
FORCEPROP 1 LAST LOCATION R1018
J 0
(-2780 5350);
DISPLAY 0.978723 (-2780 5350);
FORCEPROP 0 LAST $SEC 1
J 0
(-2775 5400);
DISPLAY 0.680851 (-2775 5400);
PAINT MONO (-2775 5400);
DISPLAY INVISIBLE (-2775 5400);
FORCEPROP 0 LAST CDS_SEC 1
J 0
(-2775 5400);
DISPLAY 0.680851 (-2775 5400);
DISPLAY INVISIBLE (-2775 5400);
FORCEPROP 1 LASTPIN (-2825 5325) $PN 1
J 0
(-2820 5287);
DISPLAY 0.787234 (-2820 5287);
PAINT MONO (-2820 5287);
FORCEPROP 1 LASTPIN (-2825 5125) $PN 2
J 0
(-2820 5135);
DISPLAY 0.787234 (-2820 5135);
PAINT MONO (-2820 5135);
FORCEPROP 1 LAST TOLERANCE 1%
J 0
(-2780 5250);
DISPLAY 0.787234 (-2780 5250);
FORCEPROP 1 LAST VALUE 1K
J 0
(-2780 5300);
DISPLAY 0.787234 (-2780 5300);
FORCEPROP 1 LAST PACK_TYPE 0201LF
J 0
(-2785 5050);
DISPLAY 0.787234 (-2785 5050);
FORCEPROP 1 LAST MATERIAL CHIP
J 0
(-2785 5150);
DISPLAY 0.787234 (-2785 5150);
FORCEPROP 1 LAST WATTAGE 1/20W
J 0
(-2785 5200);
DISPLAY 0.787234 (-2785 5200);
FORCEPROP 2 LAST CDS_LIB pure_quanta
J 0
(-2825 5225);
DISPLAY INVISIBLE (-2825 5225);
FORCEPROP 1 LAST PATH I68
J 0
(-2775 5400);
DISPLAY 0.978723 (-2775 5400);
PAINT WHITE (-2775 5400);
DISPLAY INVISIBLE (-2775 5400);
FORCEPROP 1 LAST PART_NUMBER CS21001FE07
J 0
(-2785 5100);
DISPLAY 0.978723 (-2785 5100);
DISPLAY INVISIBLE (-2785 5100);
FORCEADD Q_RES..2
(-2825 5975);
FORCEPROP 1 LAST LOCATION R1017
J 0
(-2780 6100);
DISPLAY 0.978723 (-2780 6100);
FORCEPROP 0 LAST $SEC 1
J 0
(-2775 6150);
DISPLAY 0.680851 (-2775 6150);
PAINT MONO (-2775 6150);
DISPLAY INVISIBLE (-2775 6150);
FORCEPROP 0 LAST CDS_SEC 1
J 0
(-2775 6150);
DISPLAY 0.680851 (-2775 6150);
DISPLAY INVISIBLE (-2775 6150);
FORCEPROP 1 LASTPIN (-2825 6075) $PN 1
J 0
(-2820 6037);
DISPLAY 0.787234 (-2820 6037);
PAINT MONO (-2820 6037);
FORCEPROP 1 LASTPIN (-2825 5875) $PN 2
J 0
(-2820 5885);
DISPLAY 0.787234 (-2820 5885);
PAINT MONO (-2820 5885);
FORCEPROP 1 LAST WATTAGE 1/20W
J 0
(-2785 5950);
DISPLAY 0.787234 (-2785 5950);
FORCEPROP 1 LAST TOLERANCE 1%
J 0
(-2780 6000);
DISPLAY 0.787234 (-2780 6000);
FORCEPROP 1 LAST VALUE 1K
J 0
(-2780 6050);
DISPLAY 0.787234 (-2780 6050);
FORCEPROP 1 LAST MATERIAL EMPTY
J 0
(-2785 5900);
DISPLAY 0.787234 (-2785 5900);
FORCEPROP 1 LAST PACK_TYPE 0201LF
J 0
(-2785 5800);
DISPLAY 0.787234 (-2785 5800);
FORCEPROP 2 LAST CDS_LIB pure_quanta
J 0
(-2825 5975);
DISPLAY INVISIBLE (-2825 5975);
FORCEPROP 1 LAST PATH I69
J 0
(-2775 6150);
DISPLAY 0.978723 (-2775 6150);
PAINT WHITE (-2775 6150);
DISPLAY INVISIBLE (-2775 6150);
FORCEPROP 1 LAST PART_NUMBER CS21001FE07
J 0
(-2785 5850);
DISPLAY 0.978723 (-2785 5850);
DISPLAY INVISIBLE (-2785 5850);
FORCEADD Q_RES..2
(-8950 5050);
FORCEPROP 1 LAST LOCATION R1028
J 0
(-8905 5175);
DISPLAY 0.787234 (-8905 5175);
FORCEPROP 0 LAST $SEC 1
J 0
(-8900 5225);
DISPLAY 0.680851 (-8900 5225);
PAINT MONO (-8900 5225);
DISPLAY INVISIBLE (-8900 5225);
FORCEPROP 0 LAST CDS_SEC 1
J 0
(-8900 5225);
DISPLAY 0.680851 (-8900 5225);
DISPLAY INVISIBLE (-8900 5225);
FORCEPROP 1 LASTPIN (-8950 5150) $PN 1
J 0
(-8945 5112);
DISPLAY 0.787234 (-8945 5112);
PAINT MONO (-8945 5112);
FORCEPROP 1 LASTPIN (-8950 4950) $PN 2
J 0
(-8945 4960);
DISPLAY 0.787234 (-8945 4960);
PAINT MONO (-8945 4960);
FORCEPROP 1 LAST VALUE 10K
J 0
(-8905 5125);
DISPLAY 0.787234 (-8905 5125);
FORCEPROP 1 LAST TOLERANCE 1%
J 0
(-8905 5075);
DISPLAY 0.787234 (-8905 5075);
FORCEPROP 1 LAST WATTAGE 1/20W
J 0
(-8910 5025);
DISPLAY 0.787234 (-8910 5025);
FORCEPROP 1 LAST MATERIAL CHIP
J 0
(-8910 4975);
DISPLAY 0.787234 (-8910 4975);
FORCEPROP 1 LAST PACK_TYPE 0201LF
J 0
(-8910 4875);
DISPLAY 0.787234 (-8910 4875);
FORCEPROP 2 LAST CDS_LIB pure_quanta
J 0
(-8950 5050);
DISPLAY INVISIBLE (-8950 5050);
FORCEPROP 1 LAST PATH I7
J 0
(-8900 5225);
DISPLAY 0.978723 (-8900 5225);
PAINT WHITE (-8900 5225);
DISPLAY INVISIBLE (-8900 5225);
FORCEPROP 1 LAST PART_NUMBER CS31001FE17
J 0
(-8910 4925);
DISPLAY 0.638298 (-8910 4925);
DISPLAY INVISIBLE (-8910 4925);
FORCEADD P1V0..1
(-3475 6425);
FORCEPROP 3 LASTPIN (-3475 6375) SIG_NAME P1V8_CPU0_RT_1D\g
J 0
(-3465 6385);
DISPLAY 0.659574 (-3465 6385);
PAINT MONO (-3465 6385);
DISPLAY INVISIBLE (-3465 6385);
FORCEPROP 1 LAST HDL_POWER P1V8_CPU0_RT_1D
J 1
(-3475 6475);
DISPLAY 0.489362 (-3475 6475);
FORCEPROP 2 LAST CDS_LIB pure_quanta_power
J 0
(-3475 6425);
DISPLAY INVISIBLE (-3475 6425);
FORCEPROP 1 LAST PATH I70
J 0
(-3425 6450);
DISPLAY 0.872340 (-3425 6450);
PAINT AQUA (-3425 6450);
DISPLAY INVISIBLE (-3425 6450);
FORCEADD GND..1
(-1300 4875);
FORCEPROP 3 LASTPIN (-1300 4925) SIG_NAME GND\g
J 0
(-1290 4935);
DISPLAY 0.659574 (-1290 4935);
PAINT MONO (-1290 4935);
DISPLAY INVISIBLE (-1290 4935);
FORCEPROP 2 LAST CDS_LIB pure_quanta_power
J 0
(-1300 4875);
DISPLAY INVISIBLE (-1300 4875);
FORCEPROP 2 LAST BOM_COST MEM
J 0
(-1400 4950);
DISPLAY 0.808511 (-1400 4950);
DISPLAY INVISIBLE (-1400 4950);
FORCEPROP 1 LAST SIZE 1B
J 0
(-1225 4825);
DISPLAY 0.851064 (-1225 4825);
PAINT GREEN (-1225 4825);
DISPLAY INVISIBLE (-1225 4825);
FORCEPROP 1 LAST HDL_POWER GND
J 0
(-1300 5025);
DISPLAY 0.851064 (-1300 5025);
PAINT GREEN (-1300 5025);
DISPLAY INVISIBLE (-1300 5025);
FORCEPROP 1 LAST PATH I71
J 0
(-1225 4875);
DISPLAY 0.872340 (-1225 4875);
PAINT AQUA (-1225 4875);
DISPLAY INVISIBLE (-1225 4875);
FORCEADD GND..1
(-1475 4850);
FORCEPROP 3 LASTPIN (-1475 4900) SIG_NAME GND\g
J 0
(-1465 4910);
DISPLAY 0.659574 (-1465 4910);
PAINT MONO (-1465 4910);
DISPLAY INVISIBLE (-1465 4910);
FORCEPROP 2 LAST BOM_COST MEM
J 0
(-1575 4925);
DISPLAY 0.808511 (-1575 4925);
DISPLAY INVISIBLE (-1575 4925);
FORCEPROP 1 LAST SIZE 1B
J 0
(-1400 4800);
DISPLAY 0.851064 (-1400 4800);
PAINT GREEN (-1400 4800);
DISPLAY INVISIBLE (-1400 4800);
FORCEPROP 2 LAST CDS_LIB pure_quanta_power
J 0
(-1475 4850);
DISPLAY INVISIBLE (-1475 4850);
FORCEPROP 1 LAST HDL_POWER GND
J 0
(-1475 5000);
DISPLAY 0.851064 (-1475 5000);
PAINT GREEN (-1475 5000);
DISPLAY INVISIBLE (-1475 5000);
FORCEPROP 1 LAST PATH I72
J 0
(-1400 4850);
DISPLAY 0.872340 (-1400 4850);
PAINT AQUA (-1400 4850);
DISPLAY INVISIBLE (-1400 4850);
FORCEADD Q_RES..2
(-1300 5225);
FORCEPROP 1 LAST LOCATION R1019
J 0
(-1255 5350);
DISPLAY 0.638298 (-1255 5350);
FORCEPROP 0 LAST $SEC 1
J 0
(-1250 5400);
DISPLAY 0.680851 (-1250 5400);
PAINT MONO (-1250 5400);
DISPLAY INVISIBLE (-1250 5400);
FORCEPROP 0 LAST CDS_SEC 1
J 0
(-1250 5400);
DISPLAY 0.680851 (-1250 5400);
DISPLAY INVISIBLE (-1250 5400);
FORCEPROP 1 LASTPIN (-1300 5325) $PN 1
J 0
(-1295 5287);
DISPLAY 0.787234 (-1295 5287);
PAINT MONO (-1295 5287);
FORCEPROP 1 LASTPIN (-1300 5125) $PN 2
J 0
(-1295 5135);
DISPLAY 0.787234 (-1295 5135);
PAINT MONO (-1295 5135);
FORCEPROP 1 LAST MATERIAL CHIP
J 0
(-1260 5150);
DISPLAY 0.638298 (-1260 5150);
FORCEPROP 1 LAST TOLERANCE 1%
J 0
(-1255 5250);
DISPLAY 0.638298 (-1255 5250);
FORCEPROP 1 LAST PACK_TYPE 0201LF
J 0
(-1260 5050);
DISPLAY 0.638298 (-1260 5050);
FORCEPROP 1 LAST VALUE 10K
J 0
(-1255 5300);
DISPLAY 0.638298 (-1255 5300);
FORCEPROP 1 LAST WATTAGE 1/20W
J 0
(-1260 5200);
DISPLAY 0.638298 (-1260 5200);
FORCEPROP 2 LAST CDS_LIB pure_quanta
J 0
(-1300 5225);
DISPLAY INVISIBLE (-1300 5225);
FORCEPROP 1 LAST PATH I73
J 0
(-1250 5400);
DISPLAY 0.978723 (-1250 5400);
PAINT WHITE (-1250 5400);
DISPLAY INVISIBLE (-1250 5400);
FORCEPROP 1 LAST PART_NUMBER CS31001FE17
J 0
(-1260 5100);
DISPLAY 0.638298 (-1260 5100);
DISPLAY INVISIBLE (-1260 5100);
FORCEADD Q_RES..2
R 2
(-1475 5225);
FORCEPROP 1 LAST LOCATION R1020
J 2
(-1520 5350);
DISPLAY 0.638298 (-1520 5350);
FORCEPROP 0 LAST $SEC 1
J 0
(-1500 5400);
DISPLAY 0.680851 (-1500 5400);
PAINT MONO (-1500 5400);
DISPLAY INVISIBLE (-1500 5400);
FORCEPROP 0 LAST CDS_SEC 1
J 0
(-1500 5400);
DISPLAY 0.680851 (-1500 5400);
DISPLAY INVISIBLE (-1500 5400);
FORCEPROP 1 LASTPIN (-1475 5325) $PN 1
J 2
(-1480 5287);
DISPLAY 0.787234 (-1480 5287);
PAINT MONO (-1480 5287);
FORCEPROP 1 LASTPIN (-1475 5125) $PN 2
J 2
(-1480 5135);
DISPLAY 0.787234 (-1480 5135);
PAINT MONO (-1480 5135);
FORCEPROP 1 LAST VALUE 10K
J 2
(-1520 5300);
DISPLAY 0.638298 (-1520 5300);
FORCEPROP 1 LAST MATERIAL CHIP
J 2
(-1515 5150);
DISPLAY 0.638298 (-1515 5150);
FORCEPROP 1 LAST PACK_TYPE 0201LF
J 2
(-1515 5050);
DISPLAY 0.638298 (-1515 5050);
FORCEPROP 1 LAST WATTAGE 1/20W
J 2
(-1515 5200);
DISPLAY 0.638298 (-1515 5200);
FORCEPROP 1 LAST TOLERANCE 1%
J 2
(-1520 5250);
DISPLAY 0.638298 (-1520 5250);
FORCEPROP 2 LAST CDS_LIB pure_quanta
J 2
(-1475 5225);
DISPLAY INVISIBLE (-1475 5225);
FORCEPROP 1 LAST PATH I74
J 2
(-1525 5400);
DISPLAY 0.978723 (-1525 5400);
PAINT WHITE (-1525 5400);
DISPLAY INVISIBLE (-1525 5400);
FORCEPROP 1 LAST PART_NUMBER CS31001FE17
J 2
(-1515 5100);
DISPLAY 0.638298 (-1515 5100);
DISPLAY INVISIBLE (-1515 5100);
FORCEADD OFFPAGE..5
R 2
(-1925 5475);
FORCEPROP 2 LAST $XR0 288 
J 0
(-1736 5475);
DISPLAY 0.638298 (-1736 5475);
PAINT MONO (-1736 5475);
FORCEPROP 2 LAST CDS_LIB standard
J 0
(-1925 5475);
DISPLAY INVISIBLE (-1925 5475);
FORCEPROP 1 LAST OFFPAGE TRUE
J 2
(-2250 5350);
DISPLAY 0.872340 (-2250 5350);
PAINT GREEN (-2250 5350);
DISPLAY INVISIBLE (-2250 5350);
FORCEPROP 1 LAST COMMENT_BODY TRUE
J 2
(-2025 5400);
DISPLAY 0.872340 (-2025 5400);
PAINT GREEN (-2025 5400);
DISPLAY INVISIBLE (-2025 5400);
FORCEPROP 2 LAST PATH I75
J 0
(-1725 5525);
DISPLAY 0.680851 (-1725 5525);
DISPLAY INVISIBLE (-1725 5525);
FORCEADD OFFPAGE..5
R 2
(-1925 5575);
FORCEPROP 2 LAST $XR0 288 
J 0
(-1736 5575);
DISPLAY 0.638298 (-1736 5575);
PAINT MONO (-1736 5575);
FORCEPROP 2 LAST CDS_LIB standard
J 0
(-1925 5575);
DISPLAY INVISIBLE (-1925 5575);
FORCEPROP 1 LAST OFFPAGE TRUE
J 2
(-2250 5450);
DISPLAY 0.872340 (-2250 5450);
PAINT GREEN (-2250 5450);
DISPLAY INVISIBLE (-2250 5450);
FORCEPROP 1 LAST COMMENT_BODY TRUE
J 2
(-2025 5500);
DISPLAY 0.872340 (-2025 5500);
PAINT GREEN (-2025 5500);
DISPLAY INVISIBLE (-2025 5500);
FORCEPROP 2 LAST PATH I76
J 0
(-1725 5625);
DISPLAY 0.680851 (-1725 5625);
DISPLAY INVISIBLE (-1725 5625);
FORCEADD OFFPAGE..5
R 2
(-1925 5675);
FORCEPROP 2 LAST $XR0 288 
J 0
(-1736 5675);
DISPLAY 0.638298 (-1736 5675);
PAINT MONO (-1736 5675);
FORCEPROP 2 LAST CDS_LIB standard
J 0
(-1925 5675);
DISPLAY INVISIBLE (-1925 5675);
FORCEPROP 1 LAST OFFPAGE TRUE
J 2
(-2250 5550);
DISPLAY 0.872340 (-2250 5550);
PAINT GREEN (-2250 5550);
DISPLAY INVISIBLE (-2250 5550);
FORCEPROP 1 LAST COMMENT_BODY TRUE
J 2
(-2025 5600);
DISPLAY 0.872340 (-2025 5600);
PAINT GREEN (-2025 5600);
DISPLAY INVISIBLE (-2025 5600);
FORCEPROP 2 LAST PATH I77
J 0
(-1725 5725);
DISPLAY 0.680851 (-1725 5725);
DISPLAY INVISIBLE (-1725 5725);
FORCEADD Q_RES..2
R 2
(-1475 6050);
FORCEPROP 1 LAST LOCATION R1023
J 2
(-1520 6175);
DISPLAY 0.787234 (-1520 6175);
FORCEPROP 0 LAST $SEC 1
J 0
(-1500 6225);
DISPLAY 0.680851 (-1500 6225);
PAINT MONO (-1500 6225);
DISPLAY INVISIBLE (-1500 6225);
FORCEPROP 0 LAST CDS_SEC 1
J 0
(-1500 6225);
DISPLAY 0.680851 (-1500 6225);
DISPLAY INVISIBLE (-1500 6225);
FORCEPROP 1 LASTPIN (-1475 6150) $PN 1
J 2
(-1480 6112);
DISPLAY 0.787234 (-1480 6112);
PAINT MONO (-1480 6112);
FORCEPROP 1 LASTPIN (-1475 5950) $PN 2
J 2
(-1480 5960);
DISPLAY 0.787234 (-1480 5960);
PAINT MONO (-1480 5960);
FORCEPROP 1 LAST TOLERANCE 5%
J 2
(-1520 6075);
DISPLAY 0.787234 (-1520 6075);
FORCEPROP 1 LAST VALUE 4.7K
J 2
(-1520 6125);
DISPLAY 0.787234 (-1520 6125);
FORCEPROP 1 LAST MATERIAL EMPTY
J 2
(-1515 5975);
DISPLAY 0.787234 (-1515 5975);
FORCEPROP 1 LAST PACK_TYPE 0201LF
J 2
(-1525 5900);
DISPLAY 0.787234 (-1525 5900);
FORCEPROP 1 LAST WATTAGE 1/20W
J 2
(-1515 6025);
DISPLAY 0.787234 (-1515 6025);
FORCEPROP 2 LAST CDS_LIB pure_quanta
J 2
(-1475 6050);
DISPLAY INVISIBLE (-1475 6050);
FORCEPROP 1 LAST PATH I78
J 2
(-1525 6225);
DISPLAY 0.978723 (-1525 6225);
PAINT WHITE (-1525 6225);
DISPLAY INVISIBLE (-1525 6225);
FORCEPROP 1 LAST PART_NUMBER CS24701JE04
J 2
(-1515 5925);
DISPLAY 0.978723 (-1515 5925);
DISPLAY INVISIBLE (-1515 5925);
FORCEADD OFFPAGE..1
R 2
(-500 5600);
FORCEPROP 2 LAST $XR1 288 
J 0
(-224 5600);
DISPLAY 0.638298 (-224 5600);
PAINT MONO (-224 5600);
FORCEPROP 2 LAST $XR0 81 
J 0
(-314 5600);
DISPLAY 0.638298 (-314 5600);
PAINT MONO (-314 5600);
FORCEPROP 2 LAST CDS_LIB standard
J 0
(-500 5600);
DISPLAY INVISIBLE (-500 5600);
FORCEPROP 1 LAST OFFPAGE TRUE
J 2
(-825 5475);
DISPLAY 0.872340 (-825 5475);
PAINT GREEN (-825 5475);
DISPLAY INVISIBLE (-825 5475);
FORCEPROP 1 LAST COMMENT_BODY TRUE
J 2
(-625 5500);
DISPLAY 0.872340 (-625 5500);
PAINT GREEN (-625 5500);
DISPLAY INVISIBLE (-625 5500);
FORCEPROP 2 LAST PATH I79
J 0
(-200 5650);
DISPLAY 0.680851 (-200 5650);
DISPLAY INVISIBLE (-200 5650);
FORCEADD Q_RES..2
(-8650 5050);
FORCEPROP 1 LAST LOCATION R1029
J 0
(-8605 5175);
DISPLAY 0.787234 (-8605 5175);
FORCEPROP 0 LAST $SEC 1
J 0
(-8600 5225);
DISPLAY 0.680851 (-8600 5225);
PAINT MONO (-8600 5225);
DISPLAY INVISIBLE (-8600 5225);
FORCEPROP 0 LAST CDS_SEC 1
J 0
(-8600 5225);
DISPLAY 0.680851 (-8600 5225);
DISPLAY INVISIBLE (-8600 5225);
FORCEPROP 1 LASTPIN (-8650 5150) $PN 1
J 0
(-8645 5112);
DISPLAY 0.787234 (-8645 5112);
PAINT MONO (-8645 5112);
FORCEPROP 1 LASTPIN (-8650 4950) $PN 2
J 0
(-8645 4960);
DISPLAY 0.787234 (-8645 4960);
PAINT MONO (-8645 4960);
FORCEPROP 1 LAST WATTAGE 1/20W
J 0
(-8610 5025);
DISPLAY 0.787234 (-8610 5025);
FORCEPROP 1 LAST PACK_TYPE 0201LF
J 0
(-8610 4875);
DISPLAY 0.787234 (-8610 4875);
FORCEPROP 1 LAST MATERIAL CHIP
J 0
(-8610 4975);
DISPLAY 0.787234 (-8610 4975);
FORCEPROP 1 LAST TOLERANCE 1%
J 0
(-8605 5075);
DISPLAY 0.787234 (-8605 5075);
FORCEPROP 1 LAST VALUE 10K
J 0
(-8605 5125);
DISPLAY 0.787234 (-8605 5125);
FORCEPROP 2 LAST CDS_LIB pure_quanta
J 0
(-8650 5050);
DISPLAY INVISIBLE (-8650 5050);
FORCEPROP 1 LAST PATH I8
J 0
(-8600 5225);
DISPLAY 0.978723 (-8600 5225);
PAINT WHITE (-8600 5225);
DISPLAY INVISIBLE (-8600 5225);
FORCEPROP 1 LAST PART_NUMBER CS31001FE17
J 0
(-8610 4925);
DISPLAY 0.510638 (-8610 4925);
DISPLAY INVISIBLE (-8610 4925);
FORCEADD OFFPAGE..1
R 2
(-525 5450);
FORCEPROP 2 LAST $XR1 288 
J 0
(-249 5450);
DISPLAY 0.638298 (-249 5450);
PAINT MONO (-249 5450);
FORCEPROP 2 LAST $XR0 81 
J 0
(-339 5450);
DISPLAY 0.638298 (-339 5450);
PAINT MONO (-339 5450);
FORCEPROP 2 LAST CDS_LIB standard
J 0
(-525 5450);
DISPLAY INVISIBLE (-525 5450);
FORCEPROP 1 LAST OFFPAGE TRUE
J 2
(-850 5325);
DISPLAY 0.872340 (-850 5325);
PAINT GREEN (-850 5325);
DISPLAY INVISIBLE (-850 5325);
FORCEPROP 1 LAST COMMENT_BODY TRUE
J 2
(-650 5350);
DISPLAY 0.872340 (-650 5350);
PAINT GREEN (-650 5350);
DISPLAY INVISIBLE (-650 5350);
FORCEPROP 2 LAST PATH I80
J 0
(-225 5500);
DISPLAY 0.680851 (-225 5500);
DISPLAY INVISIBLE (-225 5500);
FORCEADD P1V0..1
(-1475 6300);
FORCEPROP 3 LASTPIN (-1475 6250) SIG_NAME P1V8_CPU0_RT_1D\g
J 0
(-1465 6260);
DISPLAY 0.659574 (-1465 6260);
PAINT MONO (-1465 6260);
DISPLAY INVISIBLE (-1465 6260);
FORCEPROP 1 LAST HDL_POWER P1V8_CPU0_RT_1D
J 1
(-1475 6350);
DISPLAY 0.489362 (-1475 6350);
FORCEPROP 2 LAST CDS_LIB pure_quanta_power
J 0
(-1475 6300);
DISPLAY INVISIBLE (-1475 6300);
FORCEPROP 1 LAST PATH I81
J 0
(-1425 6325);
DISPLAY 0.872340 (-1425 6325);
PAINT AQUA (-1425 6325);
DISPLAY INVISIBLE (-1425 6325);
FORCEADD OFFPAGE..1
R 2
(-2400 2800);
FORCEPROP 2 LAST $XR0 288 
J 0
(-2214 2800);
DISPLAY 0.638298 (-2214 2800);
PAINT MONO (-2214 2800);
FORCEPROP 2 LAST CDS_LIB standard
J 2
(-2400 2800);
DISPLAY INVISIBLE (-2400 2800);
FORCEPROP 1 LAST OFFPAGE TRUE
J 2
(-2725 2675);
DISPLAY 0.872340 (-2725 2675);
DISPLAY INVISIBLE (-2725 2675);
FORCEPROP 1 LAST COMMENT_BODY TRUE
J 2
(-2525 2700);
DISPLAY 0.872340 (-2525 2700);
PAINT GREEN (-2525 2700);
DISPLAY INVISIBLE (-2525 2700);
FORCEPROP 2 LAST PATH I82
J 0
(-2200 2850);
DISPLAY 0.680851 (-2200 2850);
DISPLAY INVISIBLE (-2200 2850);
FORCEADD PT5161LRS..3
(-4375 2350);
FORCEPROP 1 LAST LOCATION U6011
J 0
(-4875 3975);
DISPLAY 0.723404 (-4875 3975);
PAINT SALMON (-4875 3975);
FORCEPROP 0 LAST $SEC 3
J 0
(-4875 4125);
DISPLAY 0.680851 (-4875 4125);
PAINT MONO (-4875 4125);
DISPLAY INVISIBLE (-4875 4125);
FORCEPROP 0 LAST CDS_SEC 3
J 0
(-4875 4125);
DISPLAY 0.680851 (-4875 4125);
DISPLAY INVISIBLE (-4875 4125);
FORCEPROP 0 LASTPIN (-3775 2300) $PN G35
J 0
(-3765 2310);
DISPLAY 0.680851 (-3765 2310);
PAINT MONO (-3765 2310);
FORCEPROP 0 LASTPIN (-5025 1650) $PN FF5
J 2
(-5035 1660);
DISPLAY 0.680851 (-5035 1660);
PAINT MONO (-5035 1660);
FORCEPROP 0 LASTPIN (-5025 1550) $PN FJ3
J 2
(-5035 1560);
DISPLAY 0.680851 (-5035 1560);
PAINT MONO (-5035 1560);
FORCEPROP 0 LASTPIN (-5025 3550) $PN FJ6
J 2
(-5035 3560);
DISPLAY 0.680851 (-5035 3560);
PAINT MONO (-5035 3560);
FORCEPROP 0 LASTPIN (-5025 3450) $PN FJ23
J 2
(-5035 3460);
DISPLAY 0.680851 (-5035 3460);
PAINT MONO (-5035 3460);
FORCEPROP 0 LASTPIN (-5025 3350) $PN FJ25
J 2
(-5035 3360);
DISPLAY 0.680851 (-5035 3360);
PAINT MONO (-5035 3360);
FORCEPROP 0 LASTPIN (-5025 3250) $PN FJ28
J 2
(-5035 3260);
DISPLAY 0.680851 (-5035 3260);
PAINT MONO (-5035 3260);
FORCEPROP 0 LASTPIN (-3775 1900) $PN FJ31
J 0
(-3765 1910);
DISPLAY 0.680851 (-3765 1910);
PAINT MONO (-3765 1910);
FORCEPROP 0 LASTPIN (-3775 3650) $PN B3
J 0
(-3765 3660);
DISPLAY 0.680851 (-3765 3660);
PAINT MONO (-3765 3660);
FORCEPROP 0 LASTPIN (-3775 3350) $PN B6
J 0
(-3765 3360);
DISPLAY 0.680851 (-3765 3360);
PAINT MONO (-3765 3360);
FORCEPROP 0 LASTPIN (-3775 3550) $PN B9
J 0
(-3765 3560);
DISPLAY 0.680851 (-3765 3560);
PAINT MONO (-3765 3560);
FORCEPROP 0 LASTPIN (-3775 3100) $PN FF8
J 0
(-3765 3110);
DISPLAY 0.680851 (-3765 3110);
PAINT MONO (-3765 3110);
FORCEPROP 0 LASTPIN (-3775 3450) $PN B12
J 0
(-3765 3460);
DISPLAY 0.680851 (-3765 3460);
PAINT MONO (-3765 3460);
FORCEPROP 0 LASTPIN (-3775 3250) $PN E8
J 0
(-3765 3260);
DISPLAY 0.680851 (-3765 3260);
PAINT MONO (-3765 3260);
FORCEPROP 0 LASTPIN (-3775 2800) $PN FJ9
J 0
(-3765 2810);
DISPLAY 0.680851 (-3765 2810);
PAINT MONO (-3765 2810);
FORCEPROP 0 LASTPIN (-3775 2200) $PN F2
J 0
(-3765 2210);
DISPLAY 0.680851 (-3765 2210);
PAINT MONO (-3765 2210);
FORCEPROP 0 LASTPIN (-3775 1050) $PN E18
J 0
(-3765 1060);
DISPLAY 0.680851 (-3765 1060);
PAINT MONO (-3765 1060);
FORCEPROP 0 LASTPIN (-3775 1200) $PN B16
J 0
(-3765 1210);
DISPLAY 0.680851 (-3765 1210);
PAINT MONO (-3765 1210);
FORCEPROP 0 LASTPIN (-5025 1050) $PN FF18
J 2
(-5035 1060);
DISPLAY 0.680851 (-5035 1060);
PAINT MONO (-5035 1060);
FORCEPROP 0 LASTPIN (-5025 1200) $PN FJ16
J 2
(-5035 1210);
DISPLAY 0.680851 (-5035 1210);
PAINT MONO (-5035 1210);
FORCEPROP 0 LASTPIN (-3775 2100) $PN FF11
J 0
(-3765 2110);
DISPLAY 0.680851 (-3765 2110);
PAINT MONO (-3765 2110);
FORCEPROP 0 LASTPIN (-3775 2700) $PN E11
J 0
(-3765 2710);
DISPLAY 0.680851 (-3765 2710);
PAINT MONO (-3765 2710);
FORCEPROP 0 LASTPIN (-3775 2600) $PN FF33
J 0
(-3765 2610);
DISPLAY 0.680851 (-3765 2610);
PAINT MONO (-3765 2610);
FORCEPROP 0 LASTPIN (-5025 2650) $PN F34
J 2
(-5035 2660);
DISPLAY 0.680851 (-5035 2660);
PAINT MONO (-5035 2660);
FORCEPROP 0 LASTPIN (-5025 2550) $PN B23
J 2
(-5035 2560);
DISPLAY 0.680851 (-5035 2560);
PAINT MONO (-5035 2560);
FORCEPROP 0 LASTPIN (-5025 2450) $PN B25
J 2
(-5035 2460);
DISPLAY 0.680851 (-5035 2460);
PAINT MONO (-5035 2460);
FORCEPROP 0 LASTPIN (-5025 2900) $PN B31
J 2
(-5035 2910);
DISPLAY 0.680851 (-5035 2910);
PAINT MONO (-5035 2910);
FORCEPROP 0 LASTPIN (-5025 2800) $PN B28
J 2
(-5035 2810);
DISPLAY 0.680851 (-5035 2810);
PAINT MONO (-5035 2810);
FORCEPROP 0 LASTPIN (-3775 1700) $PN E30
J 0
(-3765 1710);
DISPLAY 0.680851 (-3765 1710);
PAINT MONO (-3765 1710);
FORCEPROP 0 LASTPIN (-5025 2150) $PN FF24
J 2
(-5035 2160);
DISPLAY 0.680851 (-5035 2160);
PAINT MONO (-5035 2160);
FORCEPROP 0 LASTPIN (-5025 2050) $PN FF27
J 2
(-5035 2060);
DISPLAY 0.680851 (-5035 2060);
PAINT MONO (-5035 2060);
FORCEPROP 0 LASTPIN (-5025 1950) $PN FF30
J 2
(-5035 1960);
DISPLAY 0.680851 (-5035 1960);
PAINT MONO (-5035 1960);
FORCEPROP 2 LAST PART_TYPE SMLF
J 0
(-4875 4075);
DISPLAY 0.680851 (-4875 4075);
FORCEPROP 2 LAST VALUE PT5161LRS
J 0
(-4875 4025);
DISPLAY 0.680851 (-4875 4025);
FORCEPROP 1 LAST MATERIAL IC
J 0
(-4875 3825);
DISPLAY 0.723404 (-4875 3825);
PAINT GREEN (-4875 3825);
FORCEPROP 1 LAST NEEDS_NO_SIZE TRUE
J 0
(-4375 2350);
DISPLAY 0.723404 (-4375 2350);
PAINT GREEN (-4375 2350);
DISPLAY INVISIBLE (-4375 2350);
FORCEPROP 1 LAST CDS_LMAN_SYM_OUTLINE -500,1450,450,-1400
J 0
(-4375 2350);
DISPLAY 0.468085 (-4375 2350);
PAINT GREEN (-4375 2350);
DISPLAY INVISIBLE (-4375 2350);
FORCEPROP 2 LAST CDS_LIB pure_quanta
J 0
(-4375 2350);
DISPLAY INVISIBLE (-4375 2350);
FORCEPROP 1 LAST PATH I83
J 0
(-4375 2350);
DISPLAY 0.723404 (-4375 2350);
PAINT GREEN (-4375 2350);
DISPLAY INVISIBLE (-4375 2350);
FORCEPROP 1 LAST PART_NUMBER AJ051610U03
J 0
(-4875 3900);
DISPLAY 0.723404 (-4875 3900);
PAINT GREEN (-4875 3900);
DISPLAY INVISIBLE (-4875 3900);
FORCEADD Q_RES..1
(-2700 3250);
FORCEPROP 1 LAST LOCATION R1391
J 0
(-2825 3250);
DISPLAY 0.787234 (-2825 3250);
PAINT WHITE (-2825 3250);
FORCEPROP 0 LAST $SEC 1
J 0
(-2325 3300);
DISPLAY 0.680851 (-2325 3300);
PAINT MONO (-2325 3300);
DISPLAY INVISIBLE (-2325 3300);
FORCEPROP 0 LAST CDS_SEC 1
J 0
(-2325 3300);
DISPLAY 0.680851 (-2325 3300);
DISPLAY INVISIBLE (-2325 3300);
FORCEPROP 1 LASTPIN (-2800 3250) $PN 1
J 0
(-2788 3262);
DISPLAY 0.787234 (-2788 3262);
PAINT MONO (-2788 3262);
FORCEPROP 1 LASTPIN (-2600 3250) $PN 2
J 0
(-2638 3262);
DISPLAY 0.787234 (-2638 3262);
PAINT MONO (-2638 3262);
FORCEPROP 1 LAST VALUE 1K
J 2
(-2500 3250);
DISPLAY 0.638298 (-2500 3250);
FORCEPROP 1 LAST MATERIAL CHIP
J 0
(-2475 3250);
DISPLAY 0.638298 (-2475 3250);
FORCEPROP 1 LAST PACK_TYPE 0201LF
J 0
(-2325 3250);
DISPLAY 0.638298 (-2325 3250);
FORCEPROP 1 LAST TOLERANCE 1%
J 0
(-2700 3150);
DISPLAY 0.638298 (-2700 3150);
DISPLAY INVISIBLE (-2700 3150);
FORCEPROP 1 LAST WATTAGE 1/20W
J 2
(-2725 3100);
DISPLAY 0.638298 (-2725 3100);
DISPLAY INVISIBLE (-2725 3100);
FORCEPROP 2 LAST CDS_LIB pure_quanta
J 0
(-2700 3250);
DISPLAY INVISIBLE (-2700 3250);
FORCEPROP 1 LAST PATH I84
J 0
(-2750 3400);
DISPLAY 0.978723 (-2750 3400);
PAINT WHITE (-2750 3400);
DISPLAY INVISIBLE (-2750 3400);
FORCEPROP 1 LAST PART_NUMBER CS21001FE07
J 0
(-2750 3350);
DISPLAY 0.978723 (-2750 3350);
DISPLAY INVISIBLE (-2750 3350);
FORCEADD UNIVERSAL_GND..1
R 1
(-1950 3250);
FORCEPROP 3 LASTPIN (-2000 3250) SIG_NAME GND\g
J 0
(-1990 3260);
DISPLAY 0.659574 (-1990 3260);
PAINT MONO (-1990 3260);
DISPLAY INVISIBLE (-1990 3260);
FORCEPROP 2 LAST CDS_LIB pure_quanta_power
J 0
(-1950 3250);
DISPLAY INVISIBLE (-1950 3250);
FORCEPROP 1 LAST HDL_POWER GND
R 1
J 1
(-1875 3275);
DISPLAY 0.872340 (-1875 3275);
PAINT GREEN (-1875 3275);
DISPLAY INVISIBLE (-1875 3275);
FORCEPROP 1 LAST PATH I88
R 1
J 0
(-1950 3325);
DISPLAY 0.872340 (-1950 3325);
PAINT AQUA (-1950 3325);
DISPLAY INVISIBLE (-1950 3325);
FORCEADD Q_RES..2
(-8325 5050);
FORCEPROP 1 LAST LOCATION R1031
J 0
(-8280 5175);
DISPLAY 0.787234 (-8280 5175);
FORCEPROP 0 LAST $SEC 1
J 0
(-8275 5225);
DISPLAY 0.680851 (-8275 5225);
PAINT MONO (-8275 5225);
DISPLAY INVISIBLE (-8275 5225);
FORCEPROP 0 LAST CDS_SEC 1
J 0
(-8275 5225);
DISPLAY 0.680851 (-8275 5225);
DISPLAY INVISIBLE (-8275 5225);
FORCEPROP 1 LASTPIN (-8325 5150) $PN 1
J 0
(-8320 5112);
DISPLAY 0.787234 (-8320 5112);
PAINT MONO (-8320 5112);
FORCEPROP 1 LASTPIN (-8325 4950) $PN 2
J 0
(-8320 4960);
DISPLAY 0.787234 (-8320 4960);
PAINT MONO (-8320 4960);
FORCEPROP 1 LAST PACK_TYPE 0201LF
J 0
(-8285 4875);
DISPLAY 0.787234 (-8285 4875);
FORCEPROP 1 LAST MATERIAL CHIP
J 0
(-8285 4975);
DISPLAY 0.787234 (-8285 4975);
FORCEPROP 1 LAST WATTAGE 1/20W
J 0
(-8285 5025);
DISPLAY 0.787234 (-8285 5025);
FORCEPROP 1 LAST VALUE 4.7K
J 0
(-8280 5125);
DISPLAY 0.787234 (-8280 5125);
FORCEPROP 1 LAST TOLERANCE 5%
J 0
(-8280 5075);
DISPLAY 0.787234 (-8280 5075);
FORCEPROP 2 LAST CDS_LIB pure_quanta
J 0
(-8325 5050);
DISPLAY INVISIBLE (-8325 5050);
FORCEPROP 1 LAST PATH I9
J 0
(-8275 5225);
DISPLAY 0.978723 (-8275 5225);
PAINT WHITE (-8275 5225);
DISPLAY INVISIBLE (-8275 5225);
FORCEPROP 1 LAST PART_NUMBER CS24701JE04
J 0
(-8285 4925);
DISPLAY 0.978723 (-8285 4925);
DISPLAY INVISIBLE (-8285 4925);
FORCEADD Q_RES..1
(-2675 2300);
FORCEPROP 1 LAST LOCATION R1395
J 0
(-2725 2350);
DISPLAY 0.978723 (-2725 2350);
FORCEPROP 0 LAST $SEC 1
J 0
(-2725 2400);
DISPLAY 0.680851 (-2725 2400);
PAINT MONO (-2725 2400);
DISPLAY INVISIBLE (-2725 2400);
FORCEPROP 0 LAST CDS_SEC 1
J 0
(-2725 2400);
DISPLAY 0.680851 (-2725 2400);
DISPLAY INVISIBLE (-2725 2400);
FORCEPROP 1 LASTPIN (-2775 2300) $PN 1
J 0
(-2763 2312);
DISPLAY 0.787234 (-2763 2312);
PAINT MONO (-2763 2312);
FORCEPROP 1 LASTPIN (-2575 2300) $PN 2
J 0
(-2613 2312);
DISPLAY 0.787234 (-2613 2312);
PAINT MONO (-2613 2312);
FORCEPROP 1 LAST PACK_TYPE 0201LF
J 0
(-2250 2300);
DISPLAY 0.638298 (-2250 2300);
FORCEPROP 1 LAST VALUE 4.7K
J 2
(-2425 2300);
DISPLAY 0.638298 (-2425 2300);
FORCEPROP 1 LAST MATERIAL CHIP
J 0
(-2400 2300);
DISPLAY 0.638298 (-2400 2300);
FORCEPROP 1 LAST WATTAGE 1/20W
J 2
(-2700 2150);
DISPLAY 0.978723 (-2700 2150);
DISPLAY INVISIBLE (-2700 2150);
FORCEPROP 1 LAST TOLERANCE 5%
J 0
(-2675 2200);
DISPLAY 0.978723 (-2675 2200);
DISPLAY INVISIBLE (-2675 2200);
FORCEPROP 2 LAST CDS_LIB pure_quanta
J 0
(-2675 2300);
DISPLAY INVISIBLE (-2675 2300);
FORCEPROP 1 LAST PATH I94
J 0
(-2725 2450);
DISPLAY 0.978723 (-2725 2450);
PAINT WHITE (-2725 2450);
DISPLAY INVISIBLE (-2725 2450);
FORCEPROP 1 LAST PART_NUMBER CS24701JE04
J 0
(-2725 2400);
DISPLAY 0.978723 (-2725 2400);
DISPLAY INVISIBLE (-2725 2400);
FORCEADD UNIVERSAL_GND..1
R 1
(-1950 2300);
FORCEPROP 3 LASTPIN (-2000 2300) SIG_NAME GND\g
J 0
(-1990 2310);
DISPLAY 0.659574 (-1990 2310);
PAINT MONO (-1990 2310);
DISPLAY INVISIBLE (-1990 2310);
FORCEPROP 2 LAST CDS_LIB pure_quanta_power
J 0
(-1950 2300);
DISPLAY INVISIBLE (-1950 2300);
FORCEPROP 1 LAST HDL_POWER GND
R 1
J 1
(-1875 2325);
DISPLAY 0.872340 (-1875 2325);
PAINT GREEN (-1875 2325);
DISPLAY INVISIBLE (-1875 2325);
FORCEPROP 1 LAST PATH I95
R 1
J 0
(-1950 2375);
DISPLAY 0.872340 (-1950 2375);
PAINT AQUA (-1950 2375);
DISPLAY INVISIBLE (-1950 2375);
FORCEADD OFFPAGE..1
R 2
(-2400 2700);
FORCEPROP 2 LAST $XR0 288 
J 0
(-2214 2700);
DISPLAY 0.638298 (-2214 2700);
PAINT MONO (-2214 2700);
FORCEPROP 2 LAST CDS_LIB standard
J 0
(-2400 2700);
DISPLAY INVISIBLE (-2400 2700);
FORCEPROP 1 LAST OFFPAGE TRUE
J 2
(-2725 2575);
DISPLAY 0.872340 (-2725 2575);
DISPLAY INVISIBLE (-2725 2575);
FORCEPROP 1 LAST COMMENT_BODY TRUE
J 2
(-2525 2600);
DISPLAY 0.872340 (-2525 2600);
PAINT GREEN (-2525 2600);
DISPLAY INVISIBLE (-2525 2600);
FORCEPROP 2 LAST PATH I96
J 0
(-2225 2775);
DISPLAY 0.680851 (-2225 2775);
DISPLAY INVISIBLE (-2225 2775);
FORCEADD GND..1
(-1275 2775);
FORCEPROP 3 LASTPIN (-1275 2825) SIG_NAME GND\g
J 0
(-1265 2835);
DISPLAY 0.659574 (-1265 2835);
PAINT MONO (-1265 2835);
DISPLAY INVISIBLE (-1265 2835);
FORCEPROP 2 LAST CDS_LIB pure_quanta_power
J 0
(-1275 2775);
DISPLAY INVISIBLE (-1275 2775);
FORCEPROP 1 LAST SIZE 1B
J 0
(-1200 2725);
DISPLAY 0.851064 (-1200 2725);
PAINT GREEN (-1200 2725);
DISPLAY INVISIBLE (-1200 2725);
FORCEPROP 2 LAST BOM_COST MEM
J 0
(-1375 2850);
DISPLAY 0.808511 (-1375 2850);
DISPLAY INVISIBLE (-1375 2850);
FORCEPROP 1 LAST HDL_POWER GND
J 0
(-1275 2925);
DISPLAY 0.851064 (-1275 2925);
PAINT GREEN (-1275 2925);
DISPLAY INVISIBLE (-1275 2925);
FORCEPROP 1 LAST PATH I97
J 0
(-1200 2775);
DISPLAY 0.872340 (-1200 2775);
PAINT AQUA (-1200 2775);
DISPLAY INVISIBLE (-1200 2775);
FORCEADD Q_RES..2
(-1275 3175);
FORCEPROP 1 LAST LOCATION R1398
J 0
(-1230 3300);
DISPLAY 0.787234 (-1230 3300);
PAINT WHITE (-1230 3300);
FORCEPROP 0 LAST $SEC 1
J 0
(-1225 3350);
DISPLAY 0.680851 (-1225 3350);
PAINT MONO (-1225 3350);
DISPLAY INVISIBLE (-1225 3350);
FORCEPROP 0 LAST CDS_SEC 1
J 0
(-1225 3350);
DISPLAY 0.680851 (-1225 3350);
DISPLAY INVISIBLE (-1225 3350);
FORCEPROP 1 LASTPIN (-1275 3275) $PN 1
J 0
(-1270 3237);
DISPLAY 0.787234 (-1270 3237);
PAINT MONO (-1270 3237);
FORCEPROP 1 LASTPIN (-1275 3075) $PN 2
J 0
(-1270 3085);
DISPLAY 0.787234 (-1270 3085);
PAINT MONO (-1270 3085);
FORCEPROP 1 LAST MATERIAL CHIP
J 0
(-1235 3100);
DISPLAY 0.787234 (-1235 3100);
FORCEPROP 1 LAST WATTAGE 1/20W
J 0
(-1235 3150);
DISPLAY 0.787234 (-1235 3150);
FORCEPROP 1 LAST TOLERANCE 1%
J 0
(-1230 3200);
DISPLAY 0.787234 (-1230 3200);
FORCEPROP 1 LAST VALUE 10K
J 0
(-1230 3250);
DISPLAY 0.787234 (-1230 3250);
FORCEPROP 1 LAST PACK_TYPE 0201LF
J 0
(-1235 3000);
DISPLAY 0.787234 (-1235 3000);
FORCEPROP 2 LAST CDS_LIB pure_quanta
J 0
(-1275 3175);
DISPLAY INVISIBLE (-1275 3175);
FORCEPROP 1 LAST PATH I98
J 0
(-1225 3350);
DISPLAY 0.978723 (-1225 3350);
PAINT WHITE (-1225 3350);
DISPLAY INVISIBLE (-1225 3350);
FORCEPROP 1 LAST PART_NUMBER CS31001FE17
J 0
(-1235 3050);
DISPLAY 0.510638 (-1235 3050);
DISPLAY INVISIBLE (-1235 3050);
FORCEADD Q_RES..2
(-1275 3700);
FORCEPROP 1 LAST LOCATION R1397
J 0
(-1230 3825);
DISPLAY 0.787234 (-1230 3825);
PAINT WHITE (-1230 3825);
FORCEPROP 0 LAST $SEC 1
J 0
(-1225 3875);
DISPLAY 0.680851 (-1225 3875);
PAINT MONO (-1225 3875);
DISPLAY INVISIBLE (-1225 3875);
FORCEPROP 0 LAST CDS_SEC 1
J 0
(-1225 3875);
DISPLAY 0.680851 (-1225 3875);
DISPLAY INVISIBLE (-1225 3875);
FORCEPROP 1 LASTPIN (-1275 3800) $PN 1
J 0
(-1270 3762);
DISPLAY 0.787234 (-1270 3762);
PAINT MONO (-1270 3762);
FORCEPROP 1 LASTPIN (-1275 3600) $PN 2
J 0
(-1270 3610);
DISPLAY 0.787234 (-1270 3610);
PAINT MONO (-1270 3610);
FORCEPROP 1 LAST PACK_TYPE 0201LF
J 0
(-1235 3525);
DISPLAY 0.787234 (-1235 3525);
FORCEPROP 1 LAST TOLERANCE 1%
J 0
(-1230 3725);
DISPLAY 0.787234 (-1230 3725);
FORCEPROP 1 LAST VALUE 1K
J 0
(-1230 3775);
DISPLAY 0.787234 (-1230 3775);
FORCEPROP 1 LAST MATERIAL EMPTY
J 0
(-1235 3625);
DISPLAY 0.787234 (-1235 3625);
PAINT RED (-1235 3625);
FORCEPROP 1 LAST WATTAGE 1/20W
J 0
(-1235 3675);
DISPLAY 0.787234 (-1235 3675);
FORCEPROP 2 LAST CDS_LIB pure_quanta
J 0
(-1275 3700);
DISPLAY INVISIBLE (-1275 3700);
FORCEPROP 1 LAST PATH I99
J 0
(-1225 3875);
DISPLAY 0.978723 (-1225 3875);
PAINT WHITE (-1225 3875);
DISPLAY INVISIBLE (-1225 3875);
FORCEPROP 1 LAST PART_NUMBER CS21001FE07
J 0
(-1235 3575);
DISPLAY 0.978723 (-1235 3575);
DISPLAY INVISIBLE (-1235 3575);
FORCEADD DNS..1
(-8925 4100);
PAINT RED (-8925 4100);
FORCEPROP 2 LAST CDS_LIB mstr_misc
J 0
(-8925 4100);
DISPLAY INVISIBLE (-8925 4100);
FORCEPROP 1 LAST COMMENT_BODY TRUE
R 1
J 0
(-8850 3875);
DISPLAY 0.872340 (-8850 3875);
PAINT GREEN (-8850 3875);
DISPLAY INVISIBLE (-8850 3875);
FORCEADD DNS..1
(-8825 5975);
PAINT RED (-8825 5975);
FORCEPROP 2 LAST CDS_LIB mstr_misc
J 0
(-8825 5975);
DISPLAY INVISIBLE (-8825 5975);
FORCEPROP 1 LAST COMMENT_BODY TRUE
R 1
J 0
(-8750 5750);
DISPLAY 0.872340 (-8750 5750);
PAINT GREEN (-8750 5750);
DISPLAY INVISIBLE (-8750 5750);
FORCEADD DNS..1
(-8225 6000);
PAINT RED (-8225 6000);
FORCEPROP 2 LAST CDS_LIB mstr_misc
J 0
(-8225 6000);
DISPLAY INVISIBLE (-8225 6000);
FORCEPROP 1 LAST COMMENT_BODY TRUE
R 1
J 0
(-8150 5775);
DISPLAY 0.872340 (-8150 5775);
PAINT GREEN (-8150 5775);
DISPLAY INVISIBLE (-8150 5775);
FORCEADD DNS..1
(-7925 5975);
PAINT RED (-7925 5975);
FORCEPROP 2 LAST CDS_LIB mstr_misc
J 0
(-7925 5975);
DISPLAY INVISIBLE (-7925 5975);
FORCEPROP 1 LAST COMMENT_BODY TRUE
R 1
J 0
(-7850 5750);
DISPLAY 0.872340 (-7850 5750);
PAINT GREEN (-7850 5750);
DISPLAY INVISIBLE (-7850 5750);
FORCEADD DNS..1
(-7650 6025);
PAINT RED (-7650 6025);
FORCEPROP 2 LAST CDS_LIB mstr_misc
J 0
(-7650 6025);
DISPLAY INVISIBLE (-7650 6025);
FORCEPROP 1 LAST COMMENT_BODY TRUE
R 1
J 0
(-7575 5800);
DISPLAY 0.872340 (-7575 5800);
PAINT GREEN (-7575 5800);
DISPLAY INVISIBLE (-7575 5800);
FORCEADD DNS..1
(-7325 5975);
PAINT RED (-7325 5975);
FORCEPROP 2 LAST CDS_LIB mstr_misc
J 0
(-7325 5975);
DISPLAY INVISIBLE (-7325 5975);
FORCEPROP 1 LAST COMMENT_BODY TRUE
R 1
J 0
(-7250 5750);
DISPLAY 0.872340 (-7250 5750);
PAINT GREEN (-7250 5750);
DISPLAY INVISIBLE (-7250 5750);
FORCEADD DNS..1
(-4950 5500);
PAINT RED (-4950 5500);
FORCEPROP 2 LAST CDS_LIB mstr_misc
J 0
(-4950 5500);
DISPLAY INVISIBLE (-4950 5500);
FORCEPROP 1 LAST COMMENT_BODY TRUE
R 1
J 0
(-4875 5275);
DISPLAY 0.872340 (-4875 5275);
PAINT GREEN (-4875 5275);
DISPLAY INVISIBLE (-4875 5275);
FORCEADD DNS..1
(-3425 5200);
PAINT RED (-3425 5200);
FORCEPROP 2 LAST CDS_LIB mstr_misc
J 0
(-3425 5200);
DISPLAY INVISIBLE (-3425 5200);
FORCEPROP 1 LAST COMMENT_BODY TRUE
R 1
J 0
(-3350 4975);
DISPLAY 0.872340 (-3350 4975);
PAINT GREEN (-3350 4975);
DISPLAY INVISIBLE (-3350 4975);
FORCEADD DNS..1
(-3125 6025);
PAINT RED (-3125 6025);
FORCEPROP 2 LAST CDS_LIB mstr_misc
J 0
(-3125 6025);
DISPLAY INVISIBLE (-3125 6025);
FORCEPROP 1 LAST COMMENT_BODY TRUE
R 1
J 0
(-3050 5800);
DISPLAY 0.872340 (-3050 5800);
PAINT GREEN (-3050 5800);
DISPLAY INVISIBLE (-3050 5800);
FORCEADD DNS..1
(-2775 6000);
PAINT RED (-2775 6000);
FORCEPROP 2 LAST CDS_LIB mstr_misc
J 0
(-2775 6000);
DISPLAY INVISIBLE (-2775 6000);
FORCEPROP 1 LAST COMMENT_BODY TRUE
R 1
J 0
(-2700 5775);
DISPLAY 0.872340 (-2700 5775);
PAINT GREEN (-2700 5775);
DISPLAY INVISIBLE (-2700 5775);
FORCEADD DNS..1
(-1475 6075);
PAINT RED (-1475 6075);
FORCEPROP 2 LAST CDS_LIB mstr_misc
J 0
(-1475 6075);
DISPLAY INVISIBLE (-1475 6075);
FORCEPROP 1 LAST COMMENT_BODY TRUE
R 1
J 0
(-1400 5850);
DISPLAY 0.872340 (-1400 5850);
PAINT GREEN (-1400 5850);
DISPLAY INVISIBLE (-1400 5850);
FORCEADD QUANTA_TITLE_BLOCK_C..1
(0 0);
FORCEPROP 0 LAST CDS_CON_LAST_MODIFIED Thu Sep 14 16:13:03 2023
J 0
(-1885 15);
DISPLAY INVISIBLE (-1885 15);
FORCEPROP 1 LAST CUSTOM_TXT_CDS <CON_LAST_MODIFIED>
J 0
(-1885 15);
DISPLAY 0.978723 (-1885 15);
FORCEPROP 2 LAST CUSTOM_TXT_CDS <XR_PAGE_TITLE>
J 0
(-7890 5250);
DISPLAY 0.638298 (-7890 5250);
PAINT PINK (-7890 5250);
DISPLAY INVISIBLE (-7890 5250);
FORCEPROP 1 LAST CUSTOM_TXT_CDS <NAME_2>
J 0
(-3175 50);
FORCEPROP 1 LAST CUSTOM_TXT_CDS <NAME_1>
J 0
(-3175 175);
FORCEPROP 1 LAST CUSTOM_TXT_CDS <Q_NUMBER>
J 0
(-1403 103);
DISPLAY 1.212766 (-1403 103);
FORCEPROP 1 LAST CUSTOM_TXT_CDS <Q_PROJ>
J 0
(-2382 102);
DISPLAY 1.212766 (-2382 102);
FORCEPROP 1 LAST CUSTOM_TXT_CDS <Q_REV>
J 0
(-184 103);
DISPLAY 1.212766 (-184 103);
FORCEPROP 1 LAST CUSTOM_TXT_CDS <CON_PAGE_NUM> OF <CON_TOTAL_PAGES>
J 0
(-446 18);
DISPLAY 0.978723 (-446 18);
FORCEPROP 1 LAST Q_TITLE RETIMER_CPU0_P1(5)
J 0
(-9366 26);
DISPLAY 2.446809 (-9366 26);
PAINT GREEN (-9366 26);
FORCEPROP 2 LAST PAGE_BORDER TRUE
J 0
(-7890 5250);
DISPLAY 0.638298 (-7890 5250);
PAINT PINK (-7890 5250);
DISPLAY INVISIBLE (-7890 5250);
FORCEPROP 1 LAST CDS_LMAN_SYM_OUTLINE -9475,6775,100,-125
J 0
(0 0);
DISPLAY 0.468085 (0 0);
PAINT GREEN (0 0);
DISPLAY INVISIBLE (0 0);
FORCEPROP 2 LAST CDS_LIB pure_quanta
J 0
(0 0);
DISPLAY INVISIBLE (0 0);
FORCEPROP 2 LAST CDS_XR_PAGE_TITLE CR-288 : @T6G_MB_LIB.T6G(SCH_1):PAGE288
J 0
(-7890 5250);
DISPLAY 0.638298 (-7890 5250);
PAINT PINK (-7890 5250);
DISPLAY INVISIBLE (-7890 5250);
FORCEPROP 1 LAST Q_DEPT BU9
J 1
(-3763 49);
DISPLAY 1.957447 (-3763 49);
PAINT GREEN (-3763 49);
DISPLAY INVISIBLE (-3763 49);
FORCEPROP 1 LAST COMMENT_BODY TRUE
J 0
(12 -13);
DISPLAY 0.978723 (12 -13);
PAINT GREEN (12 -13);
DISPLAY INVISIBLE (12 -13);
FORCEADD DNS..1
(-6425 625);
PAINT RED (-6425 625);
FORCEPROP 2 LAST CDS_LIB mstr_misc
J 0
(-6425 625);
DISPLAY INVISIBLE (-6425 625);
FORCEPROP 1 LAST COMMENT_BODY TRUE
R 1
J 0
(-6350 400);
DISPLAY 0.872340 (-6350 400);
PAINT GREEN (-6350 400);
DISPLAY INVISIBLE (-6350 400);
FORCEADD DNS..1
(-6050 675);
PAINT RED (-6050 675);
FORCEPROP 2 LAST CDS_LIB mstr_misc
J 0
(-6050 675);
DISPLAY INVISIBLE (-6050 675);
FORCEPROP 1 LAST COMMENT_BODY TRUE
R 1
J 0
(-5975 450);
DISPLAY 0.872340 (-5975 450);
PAINT GREEN (-5975 450);
DISPLAY INVISIBLE (-5975 450);
FORCEADD DNS..1
(-1200 3700);
PAINT RED (-1200 3700);
FORCEPROP 2 LAST CDS_LIB mstr_misc
J 0
(-1200 3700);
DISPLAY INVISIBLE (-1200 3700);
FORCEPROP 1 LAST COMMENT_BODY TRUE
R 1
J 0
(-1125 3475);
DISPLAY 0.872340 (-1125 3475);
PAINT GREEN (-1125 3475);
DISPLAY INVISIBLE (-1125 3475);
FORCEADD DNS..1
(-750 1375);
PAINT RED (-750 1375);
FORCEPROP 2 LAST CDS_LIB mstr_misc
J 0
(-750 1375);
DISPLAY INVISIBLE (-750 1375);
FORCEPROP 1 LAST COMMENT_BODY TRUE
R 1
J 0
(-675 1150);
DISPLAY 0.872340 (-675 1150);
PAINT GREEN (-675 1150);
DISPLAY INVISIBLE (-675 1150);
FORCEADD DNS..1
(-1025 1375);
PAINT RED (-1025 1375);
FORCEPROP 2 LAST CDS_LIB mstr_misc
J 0
(-1025 1375);
DISPLAY INVISIBLE (-1025 1375);
FORCEPROP 1 LAST COMMENT_BODY TRUE
R 1
J 0
(-950 1150);
DISPLAY 0.872340 (-950 1150);
PAINT GREEN (-950 1150);
DISPLAY INVISIBLE (-950 1150);
FORCEADD DNS..1
(-1325 1350);
PAINT RED (-1325 1350);
FORCEPROP 2 LAST CDS_LIB mstr_misc
J 0
(-1325 1350);
DISPLAY INVISIBLE (-1325 1350);
FORCEPROP 1 LAST COMMENT_BODY TRUE
R 1
J 0
(-1250 1125);
DISPLAY 0.872340 (-1250 1125);
PAINT GREEN (-1250 1125);
DISPLAY INVISIBLE (-1250 1125);
FORCEADD DNS..1
(-1625 1400);
PAINT RED (-1625 1400);
FORCEPROP 2 LAST CDS_LIB mstr_misc
J 0
(-1625 1400);
DISPLAY INVISIBLE (-1625 1400);
FORCEPROP 1 LAST COMMENT_BODY TRUE
R 1
J 0
(-1550 1175);
DISPLAY 0.872340 (-1550 1175);
PAINT GREEN (-1550 1175);
DISPLAY INVISIBLE (-1550 1175);
WIRE 16 -1 (-1275 3800)(-1275 4050);
WIRE 16 -1 (-825 625)(-825 475);
WIRE 16 -1 (-6300 625)(-6300 450);
WIRE 16 -1 (-6150 625)(-6150 450);
WIRE 16 -1 (-8975 3350)(-8975 3225);
WIRE 16 -1 (-5025 5450)(-5025 5250);
WIRE 16 -1 (-5025 6175)(-5025 6350);
WIRE 16 -1 (-3775 1700)(-3375 1700);
WIRE 16 -1 (-8975 4225)(-8975 4400);
WIRE 16 -1 (-1300 5125)(-1300 4925);
WIRE 16 -1 (-1475 5125)(-1475 4900);
WIRE 16 -1 (-1475 6250)(-1475 6150);
WIRE 16 -1 (-2600 3250)(-2000 3250);
WIRE 16 -1 (-2575 2300)(-2000 2300);
WIRE 16 -1 (-1275 3075)(-1275 2825);
WIRE 16 -1 (-6425 1650)(-7775 1650);
FORCEPROP 2 LAST SIG_NAME SMB_RT_CPU0_P1_ROM_MUX_1D_SCL
J 0
(-7685 1660);
DISPLAY 0.680851 (-7685 1660);
WIRE 16 -1 (-5025 1650)(-6225 1650);
FORCEPROP 2 LAST SIG_NAME SMB_RT_CPU0_P1_ROM_MUX_1D_R_SCL
J 0
(-6185 1675);
DISPLAY 0.680851 (-6185 1675);
FORCEPROP 2 LASTPROP $XRERR UNIQUE?
J 0
(-6425 1675);
DISPLAY 0.638298 (-6425 1675);
PAINT MONO (-6425 1675);
DISPLAY INVISIBLE (-6425 1675);
WIRE 16 -1 (-6425 1550)(-7750 1550);
FORCEPROP 2 LAST SIG_NAME SMB_RT_CPU0_P1_ROM_MUX_1D_SDA
J 0
(-7685 1560);
DISPLAY 0.680851 (-7685 1560);
WIRE 16 -1 (-5025 1550)(-6225 1550);
FORCEPROP 2 LAST SIG_NAME SMB_RT_CPU0_P1_ROM_MUX_1D_R_SDA
J 0
(-6185 1575);
DISPLAY 0.680851 (-6185 1575);
FORCEPROP 2 LASTPROP $XRERR UNIQUE?
J 0
(-6425 1575);
DISPLAY 0.638298 (-6425 1575);
PAINT MONO (-6425 1575);
DISPLAY INVISIBLE (-6425 1575);
WIRE 16 -1 (-7850 3900)(-8975 3900);
FORCEPROP 2 LAST SIG_NAME RT_CPU0_P1_SCAN_MODE
J 0
(-8585 3910);
DISPLAY 0.680851 (-8585 3910);
WIRE 16 -1 (-8975 4025)(-8975 3900);
WIRE 16 -1 (-8975 3900)(-8975 3550);
WIRE 16 -1 (-3775 2100)(-2675 2100);
FORCEPROP 2 LAST SIG_NAME RST_RT_CPU0_P1_RESET_N
J 0
(-3585 2110);
DISPLAY 0.680851 (-3585 2110);
FORCEPROP 2 LASTPROP $XRERR UNIQUE?
J 0
(-3825 2110);
DISPLAY 0.638298 (-3825 2110);
PAINT MONO (-3825 2110);
DISPLAY INVISIBLE (-3825 2110);
WIRE 16 -1 (-3175 6325)(-2825 6325);
WIRE 16 -1 (-3475 6325)(-3175 6325);
WIRE 16 -1 (-3175 6325)(-3175 6100);
WIRE 16 -1 (-2825 6325)(-2825 6075);
WIRE 16 -1 (-3475 6100)(-3475 6325);
WIRE 16 -1 (-3475 6325)(-3475 6375);
WIRE 16 -1 (-2825 5125)(-2825 4950);
WIRE 16 -1 (-2825 4950)(-3175 4950);
WIRE 16 -1 (-3175 5125)(-3175 4950);
WIRE 16 -1 (-3175 4950)(-3475 4950);
WIRE 16 -1 (-3475 5125)(-3475 4950);
WIRE 16 -1 (-3475 4950)(-3475 4850);
WIRE 16 -1 (-8950 4950)(-8950 4725);
WIRE 16 -1 (-8950 4725)(-8650 4725);
WIRE 16 -1 (-8650 4725)(-8325 4725);
WIRE 16 -1 (-8650 4950)(-8650 4725);
WIRE 16 -1 (-8025 4725)(-8325 4725);
WIRE 16 -1 (-8325 4950)(-8325 4725);
WIRE 16 -1 (-7725 4725)(-8025 4725);
WIRE 16 -1 (-8025 4925)(-8025 4725);
WIRE 16 -1 (-7725 4725)(-7425 4725);
WIRE 16 -1 (-7725 4925)(-7725 4725);
WIRE 16 -1 (-7425 4900)(-7425 4725);
WIRE 16 -1 (-7425 4725)(-7425 4600);
WIRE 16 -1 (-1650 1450)(-1650 1600);
WIRE 16 -1 (-1650 1600)(-1375 1600);
WIRE 16 -1 (-1375 1600)(-1100 1600);
WIRE 16 -1 (-1375 1450)(-1375 1600);
WIRE 16 -1 (-1100 1600)(-825 1600);
WIRE 16 -1 (-1100 1450)(-1100 1600);
WIRE 16 -1 (-825 1600)(-825 1625);
WIRE 16 -1 (-825 1475)(-825 1600);
WIRE 16 -1 (-7725 6300)(-7425 6300);
WIRE 16 -1 (-7725 6300)(-8025 6300);
WIRE 16 -1 (-7725 6300)(-7725 6075);
WIRE 16 -1 (-7425 6300)(-7425 6100);
WIRE 16 -1 (-8025 6300)(-8025 6050);
WIRE 16 -1 (-8025 6300)(-8325 6300);
WIRE 16 -1 (-8950 6300)(-8325 6300);
WIRE 16 -1 (-8325 6300)(-8325 6100);
WIRE 16 -1 (-8950 6350)(-8950 6300);
WIRE 16 -1 (-8950 6300)(-8950 6100);
WIRE 16 -1 (-825 1275)(-825 1100);
WIRE 16 -1 (-825 1100)(-825 825);
WIRE 16 -1 (-2750 1100)(-825 1100);
FORCEPROP 2 LAST SIG_NAME JTAG_TCK_RT_CPU0_P1
J 0
(-2585 1110);
DISPLAY 0.680851 (-2585 1110);
PAINT WHITE (-2585 1110);
WIRE 16 -1 (-1100 1250)(-1100 1050);
WIRE 16 -1 (-2750 1050)(-1100 1050);
FORCEPROP 2 LAST SIG_NAME JTAG_TDO_RT_CPU0_P1
J 0
(-2560 1060);
DISPLAY 0.680851 (-2560 1060);
PAINT WHITE (-2560 1060);
WIRE 16 -1 (-1375 1250)(-1375 1000);
WIRE 16 -1 (-2750 1000)(-1375 1000);
FORCEPROP 2 LAST SIG_NAME JTAG_TMS_RT_CPU0_P1
J 0
(-2560 1010);
DISPLAY 0.680851 (-2560 1010);
PAINT WHITE (-2560 1010);
WIRE 16 -1 (-1650 1250)(-1650 950);
WIRE 16 -1 (-2750 950)(-1650 950);
FORCEPROP 2 LAST SIG_NAME JTAG_TDI_RT_CPU0_P1
J 0
(-2585 960);
DISPLAY 0.680851 (-2585 960);
PAINT WHITE (-2585 960);
WIRE 16 -1 (-2475 2100)(-1100 2100);
FORCEPROP 2 LAST SIG_NAME RST_RT_CPU0_P1_RESET_R_N
J 0
(-1960 2110);
DISPLAY 0.680851 (-1960 2110);
WIRE 16 -1 (-2475 2200)(-1100 2200);
FORCEPROP 2 LAST SIG_NAME RST_RT_CPU0_P1_PERST_R_N
J 0
(-1935 2210);
DISPLAY 0.680851 (-1935 2210);
WIRE 16 -1 (-3775 2600)(-2425 2600);
FORCEPROP 2 LAST SIG_NAME RT_CPU0_P1_SCAN_MODE
J 0
(-3485 2610);
DISPLAY 0.680851 (-3485 2610);
WIRE 16 -1 (-5025 2450)(-5925 2450);
FORCEPROP 2 LAST SIG_NAME RT_CPU0_P1_ADDR3
J 0
(-5785 2460);
DISPLAY 0.680851 (-5785 2460);
WIRE 16 -1 (-5025 2050)(-6100 2050);
FORCEPROP 2 LAST SIG_NAME TEST1_RT_CPU0_P1
J 0
(-5785 2060);
DISPLAY 0.680851 (-5785 2060);
WIRE 16 -1 (-8325 5150)(-8325 5575);
WIRE 16 -1 (-6425 5575)(-8325 5575);
FORCEPROP 2 LAST SIG_NAME TEST0_RT_CPU0_P1
J 0
(-6985 5585);
DISPLAY 0.680851 (-6985 5585);
WIRE 16 -1 (-8325 5900)(-8325 5575);
WIRE 16 -1 (-6700 1200)(-8000 1200);
FORCEPROP 2 LAST SIG_NAME CLK_100M_RETIMER_CPU0_P1_R_DP
J 0
(-7935 1210);
DISPLAY 0.680851 (-7935 1210);
WIRE 16 -1 (-6700 1050)(-8000 1050);
FORCEPROP 2 LAST SIG_NAME CLK_100M_RETIMER_CPU0_P1_R_DN
J 0
(-7960 1060);
DISPLAY 0.680851 (-7960 1060);
WIRE 16 -1 (-5025 1200)(-6150 1200);
FORCEPROP 2 LAST SIG_NAME CLK_100M_RETIMER_CPU0_P1_DP
J 0
(-6060 1210);
DISPLAY 0.680851 (-6060 1210);
FORCEPROP 2 LASTPROP $XRERR UNIQUE?
J 0
(-6300 1210);
DISPLAY 0.638298 (-6300 1210);
PAINT MONO (-6300 1210);
DISPLAY INVISIBLE (-6300 1210);
WIRE 16 -1 (-6150 1200)(-6500 1200);
WIRE 16 -1 (-6150 1200)(-6150 825);
WIRE 16 -1 (-5025 1050)(-6300 1050);
FORCEPROP 2 LAST SIG_NAME CLK_100M_RETIMER_CPU0_P1_DN
J 0
(-6060 1060);
DISPLAY 0.680851 (-6060 1060);
FORCEPROP 2 LASTPROP $XRERR UNIQUE?
J 0
(-6300 1060);
DISPLAY 0.638298 (-6300 1060);
PAINT MONO (-6300 1060);
DISPLAY INVISIBLE (-6300 1060);
WIRE 16 -1 (-6300 1050)(-6500 1050);
WIRE 16 -1 (-6300 1050)(-6300 825);
WIRE 16 -1 (-7725 5125)(-7725 5475);
WIRE 16 -1 (-6425 5475)(-7725 5475);
FORCEPROP 2 LAST SIG_NAME TEST2_RT_CPU0_P1
J 0
(-6985 5485);
DISPLAY 0.680851 (-6985 5485);
WIRE 16 -1 (-7725 5875)(-7725 5475);
WIRE 16 -1 (-5025 5650)(-5025 5800);
WIRE 16 -1 (-4200 5800)(-5025 5800);
FORCEPROP 2 LAST SIG_NAME MODE_RT_CPU0_P1
J 0
(-4810 5810);
DISPLAY 0.680851 (-4810 5810);
WIRE 16 -1 (-5025 5975)(-5025 5800);
WIRE 16 -1 (-6450 2800)(-7600 2800);
FORCEPROP 2 LAST SIG_NAME SMB_RT_CPU0_P1_R_SDA
J 0
(-7435 2810);
DISPLAY 0.680851 (-7435 2810);
WIRE 16 -1 (-8950 5150)(-8950 5700);
WIRE 16 -1 (-6425 5700)(-8950 5700);
FORCEPROP 2 LAST SIG_NAME GPIO2_RT_CPU0_P1
J 0
(-6985 5710);
DISPLAY 0.680851 (-6985 5710);
WIRE 16 -1 (-8950 5900)(-8950 5700);
WIRE 16 -1 (-8025 5125)(-8025 5525);
WIRE 16 -1 (-6425 5525)(-8025 5525);
FORCEPROP 2 LAST SIG_NAME TEST1_RT_CPU0_P1
J 0
(-6985 5535);
DISPLAY 0.680851 (-6985 5535);
WIRE 16 -1 (-8025 5850)(-8025 5525);
WIRE 16 -1 (-2825 5325)(-2825 5475);
WIRE 16 -1 (-1975 5475)(-2825 5475);
FORCEPROP 2 LAST SIG_NAME RT_CPU0_P1_ADDR1
J 0
(-2760 5485);
DISPLAY 0.680851 (-2760 5485);
WIRE 16 -1 (-2825 5475)(-2825 5875);
WIRE 16 -1 (-1300 5450)(-575 5450);
WIRE 16 -1 (-1300 5325)(-1300 5450);
FORCEPROP 2 LAST SIG_NAME RST_RT_CPU0_P1_PERST_R_N
J 0
(-1335 5485);
DISPLAY 0.680851 (-1335 5485);
WIRE 16 -1 (-3175 5325)(-3175 5575);
WIRE 16 -1 (-1975 5575)(-3175 5575);
FORCEPROP 2 LAST SIG_NAME RT_CPU0_P1_ADDR2
J 0
(-2760 5585);
DISPLAY 0.680851 (-2760 5585);
WIRE 16 -1 (-3175 5575)(-3175 5900);
WIRE 16 -1 (-1975 5675)(-3475 5675);
FORCEPROP 2 LAST SIG_NAME RT_CPU0_P1_ADDR3
J 0
(-2760 5710);
DISPLAY 0.680851 (-2760 5710);
WIRE 16 -1 (-3475 5900)(-3475 5675);
WIRE 16 -1 (-3475 5675)(-3475 5325);
WIRE 16 -1 (-1475 5325)(-1475 5600);
WIRE 16 -1 (-550 5600)(-1475 5600);
FORCEPROP 2 LAST SIG_NAME RST_RT_CPU0_P1_RESET_R_N
J 0
(-1435 5635);
DISPLAY 0.680851 (-1435 5635);
WIRE 16 -1 (-1475 5950)(-1475 5600);
WIRE 16 -1 (-5025 2650)(-5925 2650);
FORCEPROP 2 LAST SIG_NAME RT_CPU0_P1_ADDR1
J 0
(-5785 2660);
DISPLAY 0.680851 (-5785 2660);
WIRE 16 -1 (-5025 2800)(-6250 2800);
FORCEPROP 2 LAST SIG_NAME SMB_RT_CPU0_P1_R2_SDA
J 0
(-6010 2810);
DISPLAY 0.680851 (-6010 2810);
FORCEPROP 2 LASTPROP $XRERR UNIQUE?
J 0
(-6250 2810);
DISPLAY 0.638298 (-6250 2810);
PAINT MONO (-6250 2810);
DISPLAY INVISIBLE (-6250 2810);
WIRE 16 -1 (-5025 2900)(-6250 2900);
FORCEPROP 2 LAST SIG_NAME SMB_RT_CPU0_P1_R2_SCL
J 0
(-6010 2910);
DISPLAY 0.680851 (-6010 2910);
FORCEPROP 2 LASTPROP $XRERR UNIQUE?
J 0
(-6250 2910);
DISPLAY 0.638298 (-6250 2910);
PAINT MONO (-6250 2910);
DISPLAY INVISIBLE (-6250 2910);
WIRE 16 -1 (-6450 2900)(-7600 2900);
FORCEPROP 2 LAST SIG_NAME SMB_RT_CPU0_P1_R_SCL
J 0
(-7435 2910);
DISPLAY 0.680851 (-7435 2910);
WIRE 16 -1 (-5025 2150)(-6100 2150);
FORCEPROP 2 LAST SIG_NAME TEST0_RT_CPU0_P1
J 0
(-5785 2160);
DISPLAY 0.680851 (-5785 2160);
WIRE 16 -1 (-5025 1950)(-6100 1950);
FORCEPROP 2 LAST SIG_NAME TEST2_RT_CPU0_P1
J 0
(-5785 1960);
DISPLAY 0.680851 (-5785 1960);
WIRE 16 -1 (-6425 5625)(-8650 5625);
FORCEPROP 2 LAST SIG_NAME GPIO3_RT_CPU0_P1
J 0
(-7010 5635);
DISPLAY 0.680851 (-7010 5635);
WIRE 16 -1 (-8650 5625)(-8650 5150);
WIRE 16 -1 (-6425 5400)(-7425 5400);
FORCEPROP 2 LAST SIG_NAME JTAG_TEST_MODE_RT_CPU0_P1
J 0
(-7235 5410);
DISPLAY 0.680851 (-7235 5410);
WIRE 16 -1 (-7425 5900)(-7425 5400);
WIRE 16 -1 (-7425 5400)(-7425 5100);
WIRE 16 -1 (-5025 2550)(-5925 2550);
FORCEPROP 2 LAST SIG_NAME RT_CPU0_P1_ADDR2
J 0
(-5785 2560);
DISPLAY 0.680851 (-5785 2560);
WIRE 16 -1 (-1275 3275)(-1275 3425);
WIRE 16 -1 (-475 3425)(-1275 3425);
FORCEPROP 2 LAST SIG_NAME RXDET_BYP_RT_CPU0_P1
J 0
(-1160 3435);
DISPLAY 0.680851 (-1160 3435);
PAINT WHITE (-1160 3435);
WIRE 16 -1 (-1275 3425)(-1275 3600);
WIRE 16 -1 (-5025 3250)(-5975 3250);
FORCEPROP 2 LAST SIG_NAME GPIO3_RT_CPU0_P1
J 0
(-5835 3260);
DISPLAY 0.680851 (-5835 3260);
WIRE 16 -1 (-5025 3350)(-5975 3350);
FORCEPROP 2 LAST SIG_NAME GPIO2_RT_CPU0_P1
J 0
(-5835 3360);
DISPLAY 0.680851 (-5835 3360);
WIRE 16 -1 (-3775 2300)(-2775 2300);
FORCEPROP 2 LAST SIG_NAME CLKREQ_RT_CPU0_P1_N
J 0
(-3510 2310);
DISPLAY 0.680851 (-3510 2310);
PAINT WHITE (-3510 2310);
FORCEPROP 2 LASTPROP $XRERR UNIQUE?
J 0
(-3750 2310);
DISPLAY 0.638298 (-3750 2310);
PAINT MONO (-3750 2310);
DISPLAY INVISIBLE (-3750 2310);
WIRE 16 -1 (-3775 2200)(-2675 2200);
FORCEPROP 2 LAST SIG_NAME RST_RT_CPU0_P1_PERST_N
J 0
(-3610 2210);
DISPLAY 0.680851 (-3610 2210);
FORCEPROP 2 LASTPROP $XRERR UNIQUE?
J 0
(-3850 2210);
DISPLAY 0.638298 (-3850 2210);
PAINT MONO (-3850 2210);
DISPLAY INVISIBLE (-3850 2210);
WIRE 16 -1 (-3775 3250)(-2800 3250);
FORCEPROP 2 LAST SIG_NAME JTAG_TRST_RT_CPU0_P1_N
J 0
(-3610 3260);
DISPLAY 0.680851 (-3610 3260);
PAINT WHITE (-3610 3260);
FORCEPROP 2 LASTPROP $XRERR UNIQUE?
J 0
(-3850 3260);
DISPLAY 0.638298 (-3850 3260);
PAINT MONO (-3850 3260);
DISPLAY INVISIBLE (-3850 3260);
WIRE 16 -1 (-3775 3350)(-2800 3350);
FORCEPROP 2 LAST SIG_NAME JTAG_TDI_RT_CPU0_P1
J 0
(-3610 3360);
DISPLAY 0.680851 (-3610 3360);
PAINT WHITE (-3610 3360);
WIRE 16 -1 (-3775 3450)(-2775 3450);
FORCEPROP 2 LAST SIG_NAME JTAG_TMS_RT_CPU0_P1
J 0
(-3585 3460);
DISPLAY 0.680851 (-3585 3460);
PAINT WHITE (-3585 3460);
WIRE 16 -1 (-3775 3550)(-2775 3550);
FORCEPROP 2 LAST SIG_NAME JTAG_TDO_RT_CPU0_P1
J 0
(-3585 3560);
DISPLAY 0.680851 (-3585 3560);
PAINT WHITE (-3585 3560);
WIRE 16 -1 (-3775 3650)(-2775 3650);
FORCEPROP 2 LAST SIG_NAME JTAG_TCK_RT_CPU0_P1
J 0
(-3610 3660);
DISPLAY 0.680851 (-3610 3660);
PAINT WHITE (-3610 3660);
WIRE 16 -1 (-3775 3100)(-2525 3100);
FORCEPROP 2 LAST SIG_NAME JTAG_TEST_MODE_RT_CPU0_P1
J 0
(-3585 3110);
DISPLAY 0.680851 (-3585 3110);
WIRE 16 -1 (-3775 2800)(-2450 2800);
FORCEPROP 2 LAST SIG_NAME MODE_RT_CPU0_P1
J 0
(-3460 2810);
DISPLAY 0.680851 (-3460 2810);
WIRE 16 -1 (-3775 2700)(-2450 2700);
FORCEPROP 2 LAST SIG_NAME RXDET_BYP_RT_CPU0_P1
J 0
(-3460 2710);
DISPLAY 0.680851 (-3460 2710);
PAINT WHITE (-3460 2710);
DOT 1 (-825 1600);
DOT 1 (-825 1100);
DOT 1 (-1100 1600);
DOT 1 (-1375 1600);
DOT 1 (-8975 3900);
DOT 1 (-1275 3425);
DOT 1 (-7725 4725);
DOT 1 (-6150 1200);
DOT 1 (-8650 4725);
DOT 1 (-8325 4725);
DOT 1 (-8950 5700);
DOT 1 (-8325 5575);
DOT 1 (-8950 6300);
DOT 1 (-8325 6300);
DOT 1 (-8025 4725);
DOT 1 (-8025 5525);
DOT 1 (-7725 5475);
DOT 1 (-7425 5400);
DOT 1 (-7725 6300);
DOT 1 (-8025 6300);
DOT 1 (-5025 5800);
DOT 1 (-3475 4950);
DOT 1 (-3175 4950);
DOT 1 (-3475 5675);
DOT 1 (-3175 5575);
DOT 1 (-2825 5475);
DOT 1 (-3175 6325);
DOT 1 (-1475 5600);
DOT 1 (-6300 1050);
DOT 1 (-3475 6325);
DOT 1 (-7425 4725);
FORCENOTE
CPU1 P0 RT ADDR: 0X48 (8-BIT) / 0X24 (7-BIT)
(-4275 4625) 0;
DISPLAY LEFT (-4275 4625);
DISPLAY 1.595745 (-4275 4625);
QUIT
